G04 ================== begin FILE IDENTIFICATION RECORD ==================*
G04 Layout Name:  D:/<user>/Wistron_project/16317-1/gbr/16317-1.brd*
G04 Film Name:    SE_REF_L3*
G04 File Format:  Gerber RS274X*
G04 File Origin:  Cadence Allegro 16.5-S056*
G04 Origin Date:  Fri Jun 09 15:54:00 2017*
G04 *
G04 Layer:  BOARD GEOMETRY/SE_REF_L3_TBL*
G04 Layer:  BOARD GEOMETRY/SE_REF_L3_L3*
G04 Layer:  BOARD GEOMETRY/PANEL_OUTLINE*
G04 *
G04 Offset:    (0.00 0.00)*
G04 Mirror:    No*
G04 Mode:      Positive*
G04 Rotation:  0*
G04 FullContactRelief:  No*
G04 UndefLineWidth:     6.00*
G04 ================== end FILE IDENTIFICATION RECORD ====================*
%FSLAX35Y35*MOIN*%
%IR0*IPPOS*OFA0.00000B0.00000*MIA0B0*SFA1.00000B1.00000*%
%ADD10C,.02*%
%ADD11C,.006*%
%ADD12C,.00575*%
G75*
%LPD*%
G75*
G54D10*
G01X1985143Y1416035D02*
X2720143D01*
G01X1985143Y1485335D02*
Y1416035D01*
G01Y1485335D02*
X2720143D01*
G01X1985143Y1450685D02*
X2720143D01*
G01X2160143Y1485335D02*
Y1416035D01*
G01X2405143Y1485335D02*
Y1416035D01*
G01X2510143Y1485335D02*
Y1416035D01*
G01X2720143Y1485335D02*
Y1416035D01*
G54D11*
G01X6250Y-33194D02*
Y-50694D01*
G01X1228Y-33194D02*
X11272D01*
G01X20038Y-50694D02*
Y-33194D01*
G01Y-41652D02*
X21130Y-40194D01*
X22222Y-39319D01*
X23968Y-39028D01*
X25278Y-39319D01*
X26807Y-40486D01*
X27462Y-42236D01*
Y-50694D01*
G01X41250Y-39028D02*
Y-50694D01*
G01Y-34361D02*
X40813Y-34069D01*
Y-33486D01*
X41250Y-33194D01*
X41687Y-33486D01*
Y-34069D01*
X41250Y-34361D01*
G01X55475Y-48653D02*
X56567Y-49819D01*
X58095Y-50694D01*
X59405D01*
X60715Y-50111D01*
X61588Y-49236D01*
X62025Y-48070D01*
X61807Y-46319D01*
X60933Y-45444D01*
X57003Y-43694D01*
X56130Y-41652D01*
X56567Y-40194D01*
X57440Y-39319D01*
X58750Y-39028D01*
X60060Y-39319D01*
X61370Y-40194D01*
G01X90693Y-55069D02*
X92222Y-56236D01*
X93968Y-56527D01*
X95496Y-56236D01*
X96807Y-54778D01*
X97680Y-52736D01*
Y-39028D01*
G01Y-41361D02*
X96807Y-40194D01*
X95496Y-39319D01*
X93968Y-39028D01*
X92222Y-39611D01*
X91130Y-40777D01*
X90256Y-42819D01*
X89820Y-44861D01*
X90038Y-46611D01*
X90912Y-48653D01*
X92222Y-50111D01*
X93968Y-50694D01*
X95278Y-50402D01*
X96807Y-49236D01*
X97680Y-48070D01*
G01X107975Y-42819D02*
X114962D01*
X114307Y-40777D01*
X113215Y-39611D01*
X111687Y-39028D01*
X110158Y-39319D01*
X108848Y-40194D01*
X107975Y-42236D01*
X107538Y-43986D01*
Y-45736D01*
X107975Y-47486D01*
X109067Y-49236D01*
X110377Y-50402D01*
X111905Y-50694D01*
X113433Y-50111D01*
X114962Y-48361D01*
G01X125693Y-50694D02*
Y-39028D01*
G01Y-41361D02*
X126785Y-40194D01*
X127877Y-39319D01*
X129405Y-39028D01*
X130496Y-39319D01*
X131807Y-40194D01*
G01X142320Y-50694D02*
Y-33194D01*
G01Y-41944D02*
X143412Y-40194D01*
X144722Y-39319D01*
X146032Y-39028D01*
X147996Y-39611D01*
X149307Y-40777D01*
X150180Y-42819D01*
Y-45152D01*
X149743Y-47486D01*
X148870Y-49236D01*
X147342Y-50402D01*
X146032Y-50694D01*
X144722Y-50402D01*
X143412Y-49528D01*
X142320Y-48070D01*
G01X160475Y-42819D02*
X167462D01*
X166807Y-40777D01*
X165715Y-39611D01*
X164187Y-39028D01*
X162658Y-39319D01*
X161348Y-40194D01*
X160475Y-42236D01*
X160038Y-43986D01*
Y-45736D01*
X160475Y-47486D01*
X161567Y-49236D01*
X162877Y-50402D01*
X164405Y-50694D01*
X165933Y-50111D01*
X167462Y-48361D01*
G01X178193Y-50694D02*
Y-39028D01*
G01Y-41361D02*
X179285Y-40194D01*
X180377Y-39319D01*
X181905Y-39028D01*
X182996Y-39319D01*
X184307Y-40194D01*
G01X216250Y-39028D02*
Y-50694D01*
G01Y-34361D02*
X215813Y-34069D01*
Y-33486D01*
X216250Y-33194D01*
X216687Y-33486D01*
Y-34069D01*
X216250Y-34361D01*
G01X230475Y-48653D02*
X231567Y-49819D01*
X233095Y-50694D01*
X234405D01*
X235715Y-50111D01*
X236588Y-49236D01*
X237025Y-48070D01*
X236807Y-46319D01*
X235933Y-45444D01*
X232003Y-43694D01*
X231130Y-41652D01*
X231567Y-40194D01*
X232440Y-39319D01*
X233750Y-39028D01*
X235060Y-39319D01*
X236370Y-40194D01*
G01X265256Y-55069D02*
X266785Y-56236D01*
X268095Y-56527D01*
X269842Y-55944D01*
X271152Y-54486D01*
X271807Y-51860D01*
Y-39028D01*
G01Y-34361D02*
X271370Y-34069D01*
Y-33486D01*
X271807Y-33194D01*
X272243Y-33486D01*
Y-34069D01*
X271807Y-34361D01*
G01X282538Y-39028D02*
Y-47194D01*
X283412Y-49236D01*
X284722Y-50402D01*
X286250Y-50694D01*
X287778Y-50402D01*
X289088Y-49236D01*
X289962Y-47194D01*
G01Y-50694D02*
Y-39028D01*
G01X300475Y-48653D02*
X301567Y-49819D01*
X303095Y-50694D01*
X304405D01*
X305715Y-50111D01*
X306588Y-49236D01*
X307025Y-48070D01*
X306807Y-46319D01*
X305933Y-45444D01*
X302003Y-43694D01*
X301130Y-41652D01*
X301567Y-40194D01*
X302440Y-39319D01*
X303750Y-39028D01*
X305060Y-39319D01*
X306370Y-40194D01*
G01X321250Y-33194D02*
Y-50694D01*
G01X318193Y-39028D02*
X324307D01*
G01X354940Y-50694D02*
Y-35819D01*
X355377Y-34361D01*
X356250Y-33486D01*
X357560Y-33194D01*
X358870Y-33777D01*
X359525Y-35236D01*
G01X356905Y-40194D02*
X352538D01*
G01X373750Y-50694D02*
X372440Y-50402D01*
X371130Y-49236D01*
X370256Y-47194D01*
X369820Y-44861D01*
X370256Y-42527D01*
X371130Y-40486D01*
X372440Y-39319D01*
X373750Y-39028D01*
X375060Y-39319D01*
X376370Y-40486D01*
X377243Y-42527D01*
X377462Y-44861D01*
X377243Y-47194D01*
X376370Y-49236D01*
X375060Y-50402D01*
X373750Y-50694D01*
G01X388193D02*
Y-39028D01*
G01Y-41361D02*
X389285Y-40194D01*
X390377Y-39319D01*
X391905Y-39028D01*
X392996Y-39319D01*
X394307Y-40194D01*
G01X421665Y-55944D02*
X422975Y-56527D01*
X424722Y-55944D01*
X425813Y-54778D01*
X426687Y-53319D01*
X427996Y-48653D01*
X430835Y-39028D01*
G01X423848D02*
X427996Y-48653D01*
G01X443750Y-50694D02*
X442440Y-50402D01*
X441130Y-49236D01*
X440256Y-47194D01*
X439820Y-44861D01*
X440256Y-42527D01*
X441130Y-40486D01*
X442440Y-39319D01*
X443750Y-39028D01*
X445060Y-39319D01*
X446370Y-40486D01*
X447243Y-42527D01*
X447462Y-44861D01*
X447243Y-47194D01*
X446370Y-49236D01*
X445060Y-50402D01*
X443750Y-50694D01*
G01X457538Y-39028D02*
Y-47194D01*
X458412Y-49236D01*
X459722Y-50402D01*
X461250Y-50694D01*
X462778Y-50402D01*
X464088Y-49236D01*
X464962Y-47194D01*
G01Y-50694D02*
Y-39028D01*
G01X475693Y-50694D02*
Y-39028D01*
G01Y-41361D02*
X476785Y-40194D01*
X477877Y-39319D01*
X479405Y-39028D01*
X480496Y-39319D01*
X481807Y-40194D01*
G01X510693Y-50694D02*
Y-39028D01*
G01Y-41361D02*
X511785Y-40194D01*
X512877Y-39319D01*
X514405Y-39028D01*
X515496Y-39319D01*
X516807Y-40194D01*
G01X527975Y-42819D02*
X534962D01*
X534307Y-40777D01*
X533215Y-39611D01*
X531687Y-39028D01*
X530158Y-39319D01*
X528848Y-40194D01*
X527975Y-42236D01*
X527538Y-43986D01*
Y-45736D01*
X527975Y-47486D01*
X529067Y-49236D01*
X530377Y-50402D01*
X531905Y-50694D01*
X533433Y-50111D01*
X534962Y-48361D01*
G01X547440Y-50694D02*
Y-35819D01*
X547877Y-34361D01*
X548750Y-33486D01*
X550060Y-33194D01*
X551370Y-33777D01*
X552025Y-35236D01*
G01X549405Y-40194D02*
X545038D01*
G01X562975Y-42819D02*
X569962D01*
X569307Y-40777D01*
X568215Y-39611D01*
X566687Y-39028D01*
X565158Y-39319D01*
X563848Y-40194D01*
X562975Y-42236D01*
X562538Y-43986D01*
Y-45736D01*
X562975Y-47486D01*
X564067Y-49236D01*
X565377Y-50402D01*
X566905Y-50694D01*
X568433Y-50111D01*
X569962Y-48361D01*
G01X580693Y-50694D02*
Y-39028D01*
G01Y-41361D02*
X581785Y-40194D01*
X582877Y-39319D01*
X584405Y-39028D01*
X585496Y-39319D01*
X586807Y-40194D01*
G01X597975Y-42819D02*
X604962D01*
X604307Y-40777D01*
X603215Y-39611D01*
X601687Y-39028D01*
X600158Y-39319D01*
X598848Y-40194D01*
X597975Y-42236D01*
X597538Y-43986D01*
Y-45736D01*
X597975Y-47486D01*
X599067Y-49236D01*
X600377Y-50402D01*
X601905Y-50694D01*
X603433Y-50111D01*
X604962Y-48361D01*
G01X615038Y-50694D02*
Y-39028D01*
G01Y-41944D02*
X615912Y-40486D01*
X617222Y-39319D01*
X618968Y-39028D01*
X620496Y-39319D01*
X621807Y-40486D01*
X622462Y-42527D01*
Y-50694D01*
G01X639743Y-40486D02*
X638215Y-39319D01*
X636905Y-39028D01*
X635158Y-39611D01*
X633848Y-40777D01*
X632975Y-42819D01*
X632756Y-44861D01*
X632975Y-46903D01*
X633848Y-48653D01*
X635158Y-50111D01*
X636905Y-50694D01*
X638433Y-50111D01*
X639743Y-48944D01*
G01X650475Y-42819D02*
X657462D01*
X656807Y-40777D01*
X655715Y-39611D01*
X654187Y-39028D01*
X652658Y-39319D01*
X651348Y-40194D01*
X650475Y-42236D01*
X650038Y-43986D01*
Y-45736D01*
X650475Y-47486D01*
X651567Y-49236D01*
X652877Y-50402D01*
X654405Y-50694D01*
X655933Y-50111D01*
X657462Y-48361D01*
G01X688750Y-33194D02*
Y-50694D01*
G01X685693Y-39028D02*
X691807D01*
G01X706250Y-50694D02*
X704940Y-50402D01*
X703630Y-49236D01*
X702756Y-47194D01*
X702320Y-44861D01*
X702756Y-42527D01*
X703630Y-40486D01*
X704940Y-39319D01*
X706250Y-39028D01*
X707560Y-39319D01*
X708870Y-40486D01*
X709743Y-42527D01*
X709962Y-44861D01*
X709743Y-47194D01*
X708870Y-49236D01*
X707560Y-50402D01*
X706250Y-50694D01*
G01X739940D02*
Y-35819D01*
X740377Y-34361D01*
X741250Y-33486D01*
X742560Y-33194D01*
X743870Y-33777D01*
X744525Y-35236D01*
G01X741905Y-40194D02*
X737538D01*
G01X758750Y-39028D02*
Y-50694D01*
G01Y-34361D02*
X758313Y-34069D01*
Y-33486D01*
X758750Y-33194D01*
X759187Y-33486D01*
Y-34069D01*
X758750Y-34361D01*
G01X772538Y-50694D02*
Y-39028D01*
G01Y-41944D02*
X773412Y-40486D01*
X774722Y-39319D01*
X776468Y-39028D01*
X777996Y-39319D01*
X779307Y-40486D01*
X779962Y-42527D01*
Y-50694D01*
G01X797680Y-33194D02*
Y-50694D01*
G01Y-48070D02*
X796807Y-49528D01*
X795496Y-50402D01*
X793968Y-50694D01*
X792222Y-50111D01*
X790912Y-48653D01*
X790038Y-46903D01*
X789820Y-44861D01*
X790038Y-42819D01*
X790912Y-41069D01*
X792222Y-39611D01*
X793968Y-39028D01*
X795496Y-39319D01*
X796588Y-39903D01*
X797680Y-41069D01*
G01X828750Y-33194D02*
Y-50694D01*
G01X825693Y-39028D02*
X831807D01*
G01X842538Y-50694D02*
Y-33194D01*
G01Y-41652D02*
X843630Y-40194D01*
X844722Y-39319D01*
X846468Y-39028D01*
X847778Y-39319D01*
X849307Y-40486D01*
X849962Y-42236D01*
Y-50694D01*
G01X860475Y-42819D02*
X867462D01*
X866807Y-40777D01*
X865715Y-39611D01*
X864187Y-39028D01*
X862658Y-39319D01*
X861348Y-40194D01*
X860475Y-42236D01*
X860038Y-43986D01*
Y-45736D01*
X860475Y-47486D01*
X861567Y-49236D01*
X862877Y-50402D01*
X864405Y-50694D01*
X865933Y-50111D01*
X867462Y-48361D01*
G01X894165D02*
X895912Y-49819D01*
X897877Y-50694D01*
X899623D01*
X901370Y-49819D01*
X902680Y-48361D01*
X903335Y-46319D01*
X902898Y-44278D01*
X901807Y-42527D01*
X899842Y-41361D01*
X897222Y-40777D01*
X895693Y-39611D01*
X895038Y-37569D01*
X895475Y-35527D01*
X896567Y-34069D01*
X898095Y-33194D01*
X899623D01*
X901152Y-33777D01*
X902462Y-35236D01*
G01X920617Y-50694D02*
X911883D01*
Y-33194D01*
X920617D01*
G01X917123Y-41652D02*
X911883D01*
G01X951250Y-39028D02*
Y-50694D01*
G01Y-34361D02*
X950813Y-34069D01*
Y-33486D01*
X951250Y-33194D01*
X951687Y-33486D01*
Y-34069D01*
X951250Y-34361D01*
G01X962200Y-50694D02*
Y-39028D01*
G01Y-42236D02*
X962855Y-40777D01*
X963947Y-39611D01*
X965475Y-39028D01*
X967003Y-39611D01*
X968095Y-40777D01*
X968750Y-42236D01*
Y-50694D01*
G01Y-42236D02*
X969405Y-40777D01*
X970496Y-39611D01*
X972025Y-39028D01*
X973553Y-39611D01*
X974645Y-40777D01*
X975300Y-42527D01*
Y-50694D01*
G01X982320Y-56527D02*
Y-39028D01*
G01Y-41652D02*
X983412Y-40194D01*
X984503Y-39319D01*
X986250Y-39028D01*
X987778Y-39319D01*
X989307Y-40777D01*
X989962Y-42819D01*
X990180Y-44861D01*
X989962Y-46903D01*
X989307Y-48944D01*
X987996Y-50111D01*
X986250Y-50694D01*
X984722Y-50402D01*
X983193Y-49528D01*
X982320Y-48361D01*
G01X1000475Y-42819D02*
X1007462D01*
X1006807Y-40777D01*
X1005715Y-39611D01*
X1004187Y-39028D01*
X1002658Y-39319D01*
X1001348Y-40194D01*
X1000475Y-42236D01*
X1000038Y-43986D01*
Y-45736D01*
X1000475Y-47486D01*
X1001567Y-49236D01*
X1002877Y-50402D01*
X1004405Y-50694D01*
X1005933Y-50111D01*
X1007462Y-48361D01*
G01X1025180Y-33194D02*
Y-50694D01*
G01Y-48070D02*
X1024307Y-49528D01*
X1022996Y-50402D01*
X1021468Y-50694D01*
X1019722Y-50111D01*
X1018412Y-48653D01*
X1017538Y-46903D01*
X1017320Y-44861D01*
X1017538Y-42819D01*
X1018412Y-41069D01*
X1019722Y-39611D01*
X1021468Y-39028D01*
X1022996Y-39319D01*
X1024088Y-39903D01*
X1025180Y-41069D01*
G01X1042680Y-50694D02*
Y-39028D01*
G01Y-41069D02*
X1041807Y-39903D01*
X1040496Y-39319D01*
X1038968Y-39028D01*
X1037440Y-39611D01*
X1036130Y-40777D01*
X1035256Y-42527D01*
X1034820Y-44861D01*
X1035256Y-47194D01*
X1036130Y-48944D01*
X1037440Y-50111D01*
X1038968Y-50694D01*
X1040496Y-50402D01*
X1041807Y-49528D01*
X1042680Y-48361D01*
G01X1052538Y-50694D02*
Y-39028D01*
G01Y-41944D02*
X1053412Y-40486D01*
X1054722Y-39319D01*
X1056468Y-39028D01*
X1057996Y-39319D01*
X1059307Y-40486D01*
X1059962Y-42527D01*
Y-50694D01*
G01X1077243Y-40486D02*
X1075715Y-39319D01*
X1074405Y-39028D01*
X1072658Y-39611D01*
X1071348Y-40777D01*
X1070475Y-42819D01*
X1070256Y-44861D01*
X1070475Y-46903D01*
X1071348Y-48653D01*
X1072658Y-50111D01*
X1074405Y-50694D01*
X1075933Y-50111D01*
X1077243Y-48944D01*
G01X1087975Y-42819D02*
X1094962D01*
X1094307Y-40777D01*
X1093215Y-39611D01*
X1091687Y-39028D01*
X1090158Y-39319D01*
X1088848Y-40194D01*
X1087975Y-42236D01*
X1087538Y-43986D01*
Y-45736D01*
X1087975Y-47486D01*
X1089067Y-49236D01*
X1090377Y-50402D01*
X1091905Y-50694D01*
X1093433Y-50111D01*
X1094962Y-48361D01*
G01X1126250Y-33194D02*
Y-50694D01*
G01X1123193Y-39028D02*
X1129307D01*
G01X1140693Y-50694D02*
Y-39028D01*
G01Y-41361D02*
X1141785Y-40194D01*
X1142877Y-39319D01*
X1144405Y-39028D01*
X1145496Y-39319D01*
X1146807Y-40194D01*
G01X1165180Y-50694D02*
Y-39028D01*
G01Y-41069D02*
X1164307Y-39903D01*
X1162996Y-39319D01*
X1161468Y-39028D01*
X1159940Y-39611D01*
X1158630Y-40777D01*
X1157756Y-42527D01*
X1157320Y-44861D01*
X1157756Y-47194D01*
X1158630Y-48944D01*
X1159940Y-50111D01*
X1161468Y-50694D01*
X1162996Y-50402D01*
X1164307Y-49528D01*
X1165180Y-48361D01*
G01X1182243Y-40486D02*
X1180715Y-39319D01*
X1179405Y-39028D01*
X1177658Y-39611D01*
X1176348Y-40777D01*
X1175475Y-42819D01*
X1175256Y-44861D01*
X1175475Y-46903D01*
X1176348Y-48653D01*
X1177658Y-50111D01*
X1179405Y-50694D01*
X1180933Y-50111D01*
X1182243Y-48944D01*
G01X1192975Y-42819D02*
X1199962D01*
X1199307Y-40777D01*
X1198215Y-39611D01*
X1196687Y-39028D01*
X1195158Y-39319D01*
X1193848Y-40194D01*
X1192975Y-42236D01*
X1192538Y-43986D01*
Y-45736D01*
X1192975Y-47486D01*
X1194067Y-49236D01*
X1195377Y-50402D01*
X1196905Y-50694D01*
X1198433Y-50111D01*
X1199962Y-48361D01*
G01X1210475Y-48653D02*
X1211567Y-49819D01*
X1213095Y-50694D01*
X1214405D01*
X1215715Y-50111D01*
X1216588Y-49236D01*
X1217025Y-48070D01*
X1216807Y-46319D01*
X1215933Y-45444D01*
X1212003Y-43694D01*
X1211130Y-41652D01*
X1211567Y-40194D01*
X1212440Y-39319D01*
X1213750Y-39028D01*
X1215060Y-39319D01*
X1216370Y-40194D01*
G01X1248750Y-39028D02*
Y-50694D01*
G01Y-34361D02*
X1248313Y-34069D01*
Y-33486D01*
X1248750Y-33194D01*
X1249187Y-33486D01*
Y-34069D01*
X1248750Y-34361D01*
G01X1262538Y-50694D02*
Y-39028D01*
G01Y-41944D02*
X1263412Y-40486D01*
X1264722Y-39319D01*
X1266468Y-39028D01*
X1267996Y-39319D01*
X1269307Y-40486D01*
X1269962Y-42527D01*
Y-50694D01*
G01X1301250D02*
Y-33194D01*
G01X1322680Y-50694D02*
Y-39028D01*
G01Y-41069D02*
X1321807Y-39903D01*
X1320496Y-39319D01*
X1318968Y-39028D01*
X1317440Y-39611D01*
X1316130Y-40777D01*
X1315256Y-42527D01*
X1314820Y-44861D01*
X1315256Y-47194D01*
X1316130Y-48944D01*
X1317440Y-50111D01*
X1318968Y-50694D01*
X1320496Y-50402D01*
X1321807Y-49528D01*
X1322680Y-48361D01*
G01X1331665Y-55944D02*
X1332975Y-56527D01*
X1334722Y-55944D01*
X1335813Y-54778D01*
X1336687Y-53319D01*
X1337996Y-48653D01*
X1340835Y-39028D01*
G01X1333848D02*
X1337996Y-48653D01*
G01X1350475Y-42819D02*
X1357462D01*
X1356807Y-40777D01*
X1355715Y-39611D01*
X1354187Y-39028D01*
X1352658Y-39319D01*
X1351348Y-40194D01*
X1350475Y-42236D01*
X1350038Y-43986D01*
Y-45736D01*
X1350475Y-47486D01*
X1351567Y-49236D01*
X1352877Y-50402D01*
X1354405Y-50694D01*
X1355933Y-50111D01*
X1357462Y-48361D01*
G01X1368193Y-50694D02*
Y-39028D01*
G01Y-41361D02*
X1369285Y-40194D01*
X1370377Y-39319D01*
X1371905Y-39028D01*
X1372996Y-39319D01*
X1374307Y-40194D01*
G01X1401883Y-33194D02*
Y-50694D01*
X1410617D01*
G01X1418947Y-47194D02*
X1420256Y-49236D01*
X1422003Y-50402D01*
X1423968Y-50694D01*
X1425715Y-50402D01*
X1427462Y-48944D01*
X1428553Y-47194D01*
X1428772Y-45444D01*
X1428335Y-43403D01*
X1426807Y-41944D01*
X1425278Y-41361D01*
X1423313D01*
G01X1425278D02*
X1426588Y-40486D01*
X1427680Y-39028D01*
X1428117Y-37278D01*
X1427680Y-35527D01*
X1426588Y-34069D01*
X1424623Y-33194D01*
X1422658Y-33486D01*
X1420693Y-34653D01*
G01X1441250Y-51277D02*
X1440813Y-50986D01*
Y-50402D01*
X1441250Y-50111D01*
X1441687Y-50402D01*
Y-50986D01*
X1441250Y-51277D01*
G01X1987108Y1497418D02*
X1988855Y1495960D01*
X1990820Y1495085D01*
X1992566D01*
X1994313Y1495960D01*
X1995623Y1497418D01*
X1996278Y1499460D01*
X1995841Y1501501D01*
X1994750Y1503252D01*
X1992785Y1504418D01*
X1990165Y1505002D01*
X1988636Y1506168D01*
X1987981Y1508210D01*
X1988418Y1510252D01*
X1989510Y1511710D01*
X1991038Y1512585D01*
X1992566D01*
X1994095Y1512002D01*
X1995405Y1510543D01*
G01X2013560Y1495085D02*
X2004826D01*
Y1512585D01*
X2013560D01*
G01X2010066Y1504127D02*
X2004826D01*
G01X2041573Y1512585D02*
X2046813D01*
G01X2044193D02*
Y1495085D01*
G01X2041573D02*
X2046813D01*
G01X2056016D02*
Y1512585D01*
X2061693Y1498002D01*
X2067370Y1512585D01*
Y1495085D01*
G01X2074826D02*
Y1512585D01*
X2080066D01*
X2081813Y1511710D01*
X2083123Y1509668D01*
X2083560Y1507335D01*
X2083123Y1505002D01*
X2082031Y1503252D01*
X2080066Y1502376D01*
X2074826D01*
G01X2101060Y1495085D02*
X2092326D01*
Y1512585D01*
X2101060D01*
G01X2097566Y1504127D02*
X2092326D01*
G01X2109390Y1495085D02*
Y1512585D01*
X2113756D01*
X2115503Y1511710D01*
X2116813Y1510543D01*
X2117905Y1508794D01*
X2118778Y1506751D01*
X2118996Y1503835D01*
X2118778Y1500918D01*
X2117905Y1498876D01*
X2116813Y1497126D01*
X2115503Y1495960D01*
X2113756Y1495085D01*
X2109390D01*
G01X2126234D02*
X2131693Y1512585D01*
X2137152Y1495085D01*
G01X2135186Y1501210D02*
X2128199D01*
G01X2144171Y1495085D02*
Y1512585D01*
X2154215Y1495085D01*
Y1512585D01*
G01X2171496Y1511126D02*
X2170186Y1512002D01*
X2168658Y1512585D01*
X2166911D01*
X2164946Y1511710D01*
X2163418Y1510252D01*
X2162326Y1508501D01*
X2161453Y1505585D01*
X2161234Y1502960D01*
X2161671Y1500335D01*
X2162326Y1498585D01*
X2163636Y1496835D01*
X2165165Y1495668D01*
X2166693Y1495085D01*
X2168221D01*
X2169750Y1495668D01*
X2171060Y1496543D01*
X2172152Y1497709D01*
G01X2188560Y1495085D02*
X2179826D01*
Y1512585D01*
X2188560D01*
G01X2185066Y1504127D02*
X2179826D01*
G01X2219193Y1512585D02*
Y1495085D01*
G01X2214171Y1512585D02*
X2224215D01*
G01X2231234Y1495085D02*
X2236693Y1512585D01*
X2242152Y1495085D01*
G01X2240186Y1501210D02*
X2233199D01*
G01X2255939Y1504418D02*
X2256813Y1505293D01*
X2257468Y1506751D01*
X2257905Y1508794D01*
X2257468Y1510543D01*
X2256595Y1511710D01*
X2255066Y1512585D01*
X2249171D01*
Y1495085D01*
X2256376D01*
X2257905Y1496251D01*
X2258778Y1498002D01*
X2259215Y1500043D01*
X2258778Y1502085D01*
X2257468Y1503835D01*
X2255939Y1504418D01*
X2249171D01*
G01X2267326Y1512585D02*
Y1495085D01*
X2276060D01*
G01X2293560D02*
X2284826D01*
Y1512585D01*
X2293560D01*
G01X2290066Y1504127D02*
X2284826D01*
G01X2306693Y1494502D02*
X2306256Y1494793D01*
Y1495377D01*
X2306693Y1495668D01*
X2307130Y1495377D01*
Y1494793D01*
X2306693Y1494502D01*
G01Y1502376D02*
X2306256Y1502668D01*
Y1503252D01*
X2306693Y1503543D01*
X2307130Y1503252D01*
Y1502668D01*
X2306693Y1502376D01*
G01X2337326Y1512585D02*
Y1495085D01*
X2346060D01*
G01X2354390Y1498585D02*
X2355699Y1496543D01*
X2357446Y1495377D01*
X2359411Y1495085D01*
X2361158Y1495377D01*
X2362905Y1496835D01*
X2363996Y1498585D01*
X2364215Y1500335D01*
X2363778Y1502376D01*
X2362250Y1503835D01*
X2360721Y1504418D01*
X2358756D01*
G01X2360721D02*
X2362031Y1505293D01*
X2363123Y1506751D01*
X2363560Y1508501D01*
X2363123Y1510252D01*
X2362031Y1511710D01*
X2360066Y1512585D01*
X2358101Y1512293D01*
X2356136Y1511126D01*
G01X2008773Y1477935D02*
X2014013D01*
G01X2011393D02*
Y1460435D01*
G01X2008773D02*
X2014013D01*
G01X2023216D02*
Y1477935D01*
X2028893Y1463352D01*
X2034570Y1477935D01*
Y1460435D01*
G01X2042026D02*
Y1477935D01*
X2047266D01*
X2049013Y1477060D01*
X2050323Y1475018D01*
X2050760Y1472685D01*
X2050323Y1470352D01*
X2049231Y1468602D01*
X2047266Y1467726D01*
X2042026D01*
G01X2062801Y1454602D02*
X2060618Y1457518D01*
X2059526Y1460435D01*
Y1472101D01*
X2060618Y1475018D01*
X2062801Y1477935D01*
G01X2081393Y1460435D02*
X2079646Y1460727D01*
X2078118Y1461893D01*
X2076808Y1463643D01*
X2075934Y1465685D01*
X2075498Y1468018D01*
Y1470352D01*
X2075934Y1472685D01*
X2076808Y1474727D01*
X2078118Y1476476D01*
X2079646Y1477643D01*
X2081393Y1477935D01*
X2083139Y1477643D01*
X2084668Y1476476D01*
X2085978Y1474727D01*
X2086852Y1472685D01*
X2087288Y1470352D01*
Y1468018D01*
X2086852Y1465685D01*
X2085978Y1463643D01*
X2084668Y1461893D01*
X2083139Y1460727D01*
X2081393Y1460435D01*
G01X2095181D02*
Y1477935D01*
G01Y1469477D02*
X2096273Y1470935D01*
X2097365Y1471810D01*
X2099111Y1472101D01*
X2100421Y1471810D01*
X2101950Y1470643D01*
X2102605Y1468893D01*
Y1460435D01*
G01X2109843D02*
Y1472101D01*
G01Y1468893D02*
X2110498Y1470352D01*
X2111590Y1471518D01*
X2113118Y1472101D01*
X2114646Y1471518D01*
X2115738Y1470352D01*
X2116393Y1468893D01*
Y1460435D01*
G01Y1468893D02*
X2117048Y1470352D01*
X2118139Y1471518D01*
X2119668Y1472101D01*
X2121196Y1471518D01*
X2122288Y1470352D01*
X2122943Y1468602D01*
Y1460435D01*
G01X2134985Y1454602D02*
X2137168Y1457518D01*
X2138260Y1460435D01*
Y1472101D01*
X2137168Y1475018D01*
X2134985Y1477935D01*
G01X2041590Y1428409D02*
X2042899Y1426951D01*
X2044428Y1426077D01*
X2046393Y1425785D01*
X2048358Y1426368D01*
X2049886Y1427535D01*
X2050978Y1429576D01*
X2051196Y1431910D01*
X2050760Y1434243D01*
X2049668Y1435702D01*
X2048139Y1436868D01*
X2046611Y1437160D01*
X2045083Y1436868D01*
X2043118Y1435702D01*
X2043773Y1443285D01*
X2049668D01*
G01X2063893D02*
X2062146Y1442702D01*
X2060836Y1441243D01*
X2059963Y1439494D01*
X2059308Y1437160D01*
X2059090Y1434535D01*
X2059308Y1431910D01*
X2059963Y1429576D01*
X2060836Y1427826D01*
X2062146Y1426368D01*
X2063893Y1425785D01*
X2065639Y1426368D01*
X2066950Y1427826D01*
X2067823Y1429576D01*
X2068478Y1431910D01*
X2068696Y1434535D01*
X2068478Y1437160D01*
X2067823Y1439494D01*
X2066950Y1441243D01*
X2065639Y1442702D01*
X2063893Y1443285D01*
G01X2081393Y1425202D02*
X2080956Y1425493D01*
Y1426077D01*
X2081393Y1426368D01*
X2081830Y1426077D01*
Y1425493D01*
X2081393Y1425202D01*
G01X2098893Y1443285D02*
X2097146Y1442702D01*
X2095836Y1441243D01*
X2094963Y1439494D01*
X2094308Y1437160D01*
X2094090Y1434535D01*
X2094308Y1431910D01*
X2094963Y1429576D01*
X2095836Y1427826D01*
X2097146Y1426368D01*
X2098893Y1425785D01*
X2100639Y1426368D01*
X2101950Y1427826D01*
X2102823Y1429576D01*
X2103478Y1431910D01*
X2103696Y1434535D01*
X2103478Y1437160D01*
X2102823Y1439494D01*
X2101950Y1441243D01*
X2100639Y1442702D01*
X2098893Y1443285D01*
G01X2188593Y1477935D02*
X2191649Y1460435D01*
X2195143Y1477935D01*
X2198636Y1460435D01*
X2201693Y1477935D01*
G01X2210023D02*
X2215263D01*
G01X2212643D02*
Y1460435D01*
G01X2210023D02*
X2215263D01*
G01X2225340D02*
Y1477935D01*
X2229706D01*
X2231453Y1477060D01*
X2232763Y1475893D01*
X2233855Y1474144D01*
X2234728Y1472101D01*
X2234946Y1469185D01*
X2234728Y1466268D01*
X2233855Y1464226D01*
X2232763Y1462476D01*
X2231453Y1461310D01*
X2229706Y1460435D01*
X2225340D01*
G01X2247643Y1477935D02*
Y1460435D01*
G01X2242621Y1477935D02*
X2252665D01*
G01X2260558Y1460435D02*
Y1477935D01*
G01X2269728D02*
Y1460435D01*
G01Y1469185D02*
X2260558D01*
G01X2281551Y1454602D02*
X2279368Y1457518D01*
X2278276Y1460435D01*
Y1472101D01*
X2279368Y1475018D01*
X2281551Y1477935D01*
G01X2293593Y1460435D02*
Y1472101D01*
G01Y1468893D02*
X2294248Y1470352D01*
X2295340Y1471518D01*
X2296868Y1472101D01*
X2298396Y1471518D01*
X2299488Y1470352D01*
X2300143Y1468893D01*
Y1460435D01*
G01Y1468893D02*
X2300798Y1470352D01*
X2301889Y1471518D01*
X2303418Y1472101D01*
X2304946Y1471518D01*
X2306038Y1470352D01*
X2306693Y1468602D01*
Y1460435D01*
G01X2317643Y1472101D02*
Y1460435D01*
G01Y1476768D02*
X2317206Y1477060D01*
Y1477643D01*
X2317643Y1477935D01*
X2318080Y1477643D01*
Y1477060D01*
X2317643Y1476768D01*
G01X2335143Y1460435D02*
Y1477935D01*
G01X2349368Y1462476D02*
X2350460Y1461310D01*
X2351988Y1460435D01*
X2353298D01*
X2354608Y1461018D01*
X2355481Y1461893D01*
X2355918Y1463059D01*
X2355700Y1464810D01*
X2354826Y1465685D01*
X2350896Y1467435D01*
X2350023Y1469477D01*
X2350460Y1470935D01*
X2351333Y1471810D01*
X2352643Y1472101D01*
X2353953Y1471810D01*
X2355263Y1470935D01*
G01X2371235Y1454602D02*
X2373418Y1457518D01*
X2374510Y1460435D01*
Y1472101D01*
X2373418Y1475018D01*
X2371235Y1477935D01*
G01X2251590Y1428409D02*
X2252899Y1426951D01*
X2254428Y1426077D01*
X2256393Y1425785D01*
X2258358Y1426368D01*
X2259886Y1427535D01*
X2260978Y1429576D01*
X2261196Y1431910D01*
X2260760Y1434243D01*
X2259668Y1435702D01*
X2258139Y1436868D01*
X2256611Y1437160D01*
X2255083Y1436868D01*
X2253118Y1435702D01*
X2253773Y1443285D01*
X2259668D01*
G01X2273893Y1425202D02*
X2273456Y1425493D01*
Y1426077D01*
X2273893Y1426368D01*
X2274330Y1426077D01*
Y1425493D01*
X2273893Y1425202D01*
G01X2290956Y1425785D02*
X2291393Y1429576D01*
X2292048Y1432785D01*
X2292921Y1435702D01*
X2294013Y1438910D01*
X2295760Y1443285D01*
X2287026D01*
G01X2304090Y1428409D02*
X2305399Y1426951D01*
X2306928Y1426077D01*
X2308893Y1425785D01*
X2310858Y1426368D01*
X2312386Y1427535D01*
X2313478Y1429576D01*
X2313696Y1431910D01*
X2313260Y1434243D01*
X2312168Y1435702D01*
X2310639Y1436868D01*
X2309111Y1437160D01*
X2307583Y1436868D01*
X2305618Y1435702D01*
X2306273Y1443285D01*
X2312168D01*
G01X2444308Y1428118D02*
X2446055Y1426660D01*
X2448020Y1425785D01*
X2449766D01*
X2451513Y1426660D01*
X2452823Y1428118D01*
X2453478Y1430160D01*
X2453041Y1432201D01*
X2451950Y1433952D01*
X2449985Y1435118D01*
X2447365Y1435702D01*
X2445836Y1436868D01*
X2445181Y1438910D01*
X2445618Y1440952D01*
X2446710Y1442410D01*
X2448238Y1443285D01*
X2449766D01*
X2451295Y1442702D01*
X2452605Y1441243D01*
G01X2470760Y1425785D02*
X2462026D01*
Y1443285D01*
X2470760D01*
G01X2467266Y1434827D02*
X2462026D01*
G01X2431393Y1477935D02*
Y1460435D01*
G01X2426371Y1477935D02*
X2436415D01*
G01X2448893Y1460435D02*
Y1468310D01*
X2444526Y1477935D01*
G01X2453260D02*
X2448893Y1468310D01*
G01X2462026Y1460435D02*
Y1477935D01*
X2467266D01*
X2469013Y1477060D01*
X2470323Y1475018D01*
X2470760Y1472685D01*
X2470323Y1470352D01*
X2469231Y1468602D01*
X2467266Y1467726D01*
X2462026D01*
G01X2488260Y1460435D02*
X2479526D01*
Y1477935D01*
X2488260D01*
G01X2484766Y1469477D02*
X2479526D01*
G01X2575776Y1443285D02*
Y1425785D01*
X2584510D01*
G01X2593495Y1440368D02*
X2594805Y1442118D01*
X2596333Y1442993D01*
X2598080Y1443285D01*
X2600263Y1442702D01*
X2601791Y1441243D01*
X2602228Y1439494D01*
X2602010Y1437743D01*
X2601136Y1436285D01*
X2596770Y1433368D01*
X2594805Y1431327D01*
X2593495Y1428409D01*
X2593058Y1425785D01*
X2602228D01*
G01X2611213Y1425202D02*
X2619073Y1443285D01*
G01X2628276D02*
Y1425785D01*
X2637010D01*
G01X2652763D02*
Y1443285D01*
X2644684Y1430743D01*
X2655602D01*
G01X2532026Y1460435D02*
Y1477935D01*
X2537485D01*
X2539231Y1477060D01*
X2540323Y1475893D01*
X2540760Y1473560D01*
X2540323Y1471226D01*
X2539013Y1469768D01*
X2537485Y1468893D01*
X2532026D01*
G01X2537485D02*
X2540760Y1460435D01*
G01X2550618Y1468310D02*
X2557605D01*
X2556950Y1470352D01*
X2555858Y1471518D01*
X2554330Y1472101D01*
X2552801Y1471810D01*
X2551491Y1470935D01*
X2550618Y1468893D01*
X2550181Y1467143D01*
Y1465393D01*
X2550618Y1463643D01*
X2551710Y1461893D01*
X2553020Y1460727D01*
X2554548Y1460435D01*
X2556076Y1461018D01*
X2557605Y1462768D01*
G01X2570083Y1460435D02*
Y1475310D01*
X2570520Y1476768D01*
X2571393Y1477643D01*
X2572703Y1477935D01*
X2574013Y1477352D01*
X2574668Y1475893D01*
G01X2572048Y1470935D02*
X2567681D01*
G01X2588893Y1459852D02*
X2588456Y1460143D01*
Y1460727D01*
X2588893Y1461018D01*
X2589330Y1460727D01*
Y1460143D01*
X2588893Y1459852D01*
G01X2619526Y1460435D02*
Y1477935D01*
X2624766D01*
X2626513Y1477060D01*
X2627823Y1475018D01*
X2628260Y1472685D01*
X2627823Y1470352D01*
X2626731Y1468602D01*
X2624766Y1467726D01*
X2619526D01*
G01X2641393Y1460435D02*
Y1477935D01*
G01X2662823Y1460435D02*
Y1472101D01*
G01Y1470060D02*
X2661950Y1471226D01*
X2660639Y1471810D01*
X2659111Y1472101D01*
X2657583Y1471518D01*
X2656273Y1470352D01*
X2655399Y1468602D01*
X2654963Y1466268D01*
X2655399Y1463935D01*
X2656273Y1462185D01*
X2657583Y1461018D01*
X2659111Y1460435D01*
X2660639Y1460727D01*
X2661950Y1461601D01*
X2662823Y1462768D01*
G01X2672681Y1460435D02*
Y1472101D01*
G01Y1469185D02*
X2673555Y1470643D01*
X2674865Y1471810D01*
X2676611Y1472101D01*
X2678139Y1471810D01*
X2679450Y1470643D01*
X2680105Y1468602D01*
Y1460435D01*
G01X2690618Y1468310D02*
X2697605D01*
X2696950Y1470352D01*
X2695858Y1471518D01*
X2694330Y1472101D01*
X2692801Y1471810D01*
X2691491Y1470935D01*
X2690618Y1468893D01*
X2690181Y1467143D01*
Y1465393D01*
X2690618Y1463643D01*
X2691710Y1461893D01*
X2693020Y1460727D01*
X2694548Y1460435D01*
X2696076Y1461018D01*
X2697605Y1462768D01*
G01X2811693Y1437451D02*
Y1425785D01*
G01Y1442118D02*
X2811256Y1442410D01*
Y1442993D01*
X2811693Y1443285D01*
X2812130Y1442993D01*
Y1442410D01*
X2811693Y1442118D01*
G01X2825918Y1427826D02*
X2827010Y1426660D01*
X2828538Y1425785D01*
X2829848D01*
X2831158Y1426368D01*
X2832031Y1427243D01*
X2832468Y1428409D01*
X2832250Y1430160D01*
X2831376Y1431035D01*
X2827446Y1432785D01*
X2826573Y1434827D01*
X2827010Y1436285D01*
X2827883Y1437160D01*
X2829193Y1437451D01*
X2830503Y1437160D01*
X2831813Y1436285D01*
G01X2859171Y1425785D02*
Y1443285D01*
X2869215Y1425785D01*
Y1443285D01*
G01X2881693Y1425785D02*
X2879946Y1426077D01*
X2878418Y1427243D01*
X2877108Y1428993D01*
X2876234Y1431035D01*
X2875798Y1433368D01*
Y1435702D01*
X2876234Y1438035D01*
X2877108Y1440077D01*
X2878418Y1441826D01*
X2879946Y1442993D01*
X2881693Y1443285D01*
X2883439Y1442993D01*
X2884968Y1441826D01*
X2886278Y1440077D01*
X2887152Y1438035D01*
X2887588Y1435702D01*
Y1433368D01*
X2887152Y1431035D01*
X2886278Y1428993D01*
X2884968Y1427243D01*
X2883439Y1426077D01*
X2881693Y1425785D01*
G01X2899193Y1443285D02*
Y1425785D01*
G01X2894171Y1443285D02*
X2904215D01*
G01X2930481Y1437451D02*
Y1429285D01*
X2931355Y1427243D01*
X2932665Y1426077D01*
X2934193Y1425785D01*
X2935721Y1426077D01*
X2937031Y1427243D01*
X2937905Y1429285D01*
G01Y1425785D02*
Y1437451D01*
G01X2948418Y1427826D02*
X2949510Y1426660D01*
X2951038Y1425785D01*
X2952348D01*
X2953658Y1426368D01*
X2954531Y1427243D01*
X2954968Y1428409D01*
X2954750Y1430160D01*
X2953876Y1431035D01*
X2949946Y1432785D01*
X2949073Y1434827D01*
X2949510Y1436285D01*
X2950383Y1437160D01*
X2951693Y1437451D01*
X2953003Y1437160D01*
X2954313Y1436285D01*
G01X2965918Y1433660D02*
X2972905D01*
X2972250Y1435702D01*
X2971158Y1436868D01*
X2969630Y1437451D01*
X2968101Y1437160D01*
X2966791Y1436285D01*
X2965918Y1434243D01*
X2965481Y1432493D01*
Y1430743D01*
X2965918Y1428993D01*
X2967010Y1427243D01*
X2968320Y1426077D01*
X2969848Y1425785D01*
X2971376Y1426368D01*
X2972905Y1428118D01*
G01X2990623Y1443285D02*
Y1425785D01*
G01Y1428409D02*
X2989750Y1426951D01*
X2988439Y1426077D01*
X2986911Y1425785D01*
X2985165Y1426368D01*
X2983855Y1427826D01*
X2982981Y1429576D01*
X2982763Y1431618D01*
X2982981Y1433660D01*
X2983855Y1435410D01*
X2985165Y1436868D01*
X2986911Y1437451D01*
X2988439Y1437160D01*
X2989531Y1436576D01*
X2990623Y1435410D01*
G01X2736890Y1459852D02*
X2746496Y1472685D01*
G01X2741693Y1475018D02*
Y1457518D01*
G01X2746496Y1459852D02*
X2736890Y1472685D01*
G01X2735143Y1466268D02*
X2748243D01*
G01X2773855D02*
X2779531D01*
G01X2806890Y1460435D02*
Y1477935D01*
X2811256D01*
X2813003Y1477060D01*
X2814313Y1475893D01*
X2815405Y1474144D01*
X2816278Y1472101D01*
X2816496Y1469185D01*
X2816278Y1466268D01*
X2815405Y1464226D01*
X2814313Y1462476D01*
X2813003Y1461310D01*
X2811256Y1460435D01*
X2806890D01*
G01X2825918Y1468310D02*
X2832905D01*
X2832250Y1470352D01*
X2831158Y1471518D01*
X2829630Y1472101D01*
X2828101Y1471810D01*
X2826791Y1470935D01*
X2825918Y1468893D01*
X2825481Y1467143D01*
Y1465393D01*
X2825918Y1463643D01*
X2827010Y1461893D01*
X2828320Y1460727D01*
X2829848Y1460435D01*
X2831376Y1461018D01*
X2832905Y1462768D01*
G01X2842981Y1460435D02*
Y1472101D01*
G01Y1469185D02*
X2843855Y1470643D01*
X2845165Y1471810D01*
X2846911Y1472101D01*
X2848439Y1471810D01*
X2849750Y1470643D01*
X2850405Y1468602D01*
Y1460435D01*
G01X2864193D02*
X2862883Y1460727D01*
X2861573Y1461893D01*
X2860699Y1463935D01*
X2860263Y1466268D01*
X2860699Y1468602D01*
X2861573Y1470643D01*
X2862883Y1471810D01*
X2864193Y1472101D01*
X2865503Y1471810D01*
X2866813Y1470643D01*
X2867686Y1468602D01*
X2867905Y1466268D01*
X2867686Y1463935D01*
X2866813Y1461893D01*
X2865503Y1460727D01*
X2864193Y1460435D01*
G01X2881693Y1477935D02*
Y1460435D01*
G01X2878636Y1472101D02*
X2884750D01*
G01X2895918Y1468310D02*
X2902905D01*
X2902250Y1470352D01*
X2901158Y1471518D01*
X2899630Y1472101D01*
X2898101Y1471810D01*
X2896791Y1470935D01*
X2895918Y1468893D01*
X2895481Y1467143D01*
Y1465393D01*
X2895918Y1463643D01*
X2897010Y1461893D01*
X2898320Y1460727D01*
X2899848Y1460435D01*
X2901376Y1461018D01*
X2902905Y1462768D01*
G01X2913418Y1462476D02*
X2914510Y1461310D01*
X2916038Y1460435D01*
X2917348D01*
X2918658Y1461018D01*
X2919531Y1461893D01*
X2919968Y1463059D01*
X2919750Y1464810D01*
X2918876Y1465685D01*
X2914946Y1467435D01*
X2914073Y1469477D01*
X2914510Y1470935D01*
X2915383Y1471810D01*
X2916693Y1472101D01*
X2918003Y1471810D01*
X2919313Y1470935D01*
G01X2951693Y1477935D02*
Y1460435D01*
G01X2948636Y1472101D02*
X2954750D01*
G01X2965481Y1460435D02*
Y1477935D01*
G01Y1469477D02*
X2966573Y1470935D01*
X2967665Y1471810D01*
X2969411Y1472101D01*
X2970721Y1471810D01*
X2972250Y1470643D01*
X2972905Y1468893D01*
Y1460435D01*
G01X2990623D02*
Y1472101D01*
G01Y1470060D02*
X2989750Y1471226D01*
X2988439Y1471810D01*
X2986911Y1472101D01*
X2985383Y1471518D01*
X2984073Y1470352D01*
X2983199Y1468602D01*
X2982763Y1466268D01*
X2983199Y1463935D01*
X2984073Y1462185D01*
X2985383Y1461018D01*
X2986911Y1460435D01*
X2988439Y1460727D01*
X2989750Y1461601D01*
X2990623Y1462768D01*
G01X3004193Y1477935D02*
Y1460435D01*
G01X3001136Y1472101D02*
X3007250D01*
G01X3039193Y1477935D02*
Y1460435D01*
G01X3036136Y1472101D02*
X3042250D01*
G01X3052981Y1460435D02*
Y1477935D01*
G01Y1469477D02*
X3054073Y1470935D01*
X3055165Y1471810D01*
X3056911Y1472101D01*
X3058221Y1471810D01*
X3059750Y1470643D01*
X3060405Y1468893D01*
Y1460435D01*
G01X3074193Y1472101D02*
Y1460435D01*
G01Y1476768D02*
X3073756Y1477060D01*
Y1477643D01*
X3074193Y1477935D01*
X3074630Y1477643D01*
Y1477060D01*
X3074193Y1476768D01*
G01X3088418Y1462476D02*
X3089510Y1461310D01*
X3091038Y1460435D01*
X3092348D01*
X3093658Y1461018D01*
X3094531Y1461893D01*
X3094968Y1463059D01*
X3094750Y1464810D01*
X3093876Y1465685D01*
X3089946Y1467435D01*
X3089073Y1469477D01*
X3089510Y1470935D01*
X3090383Y1471810D01*
X3091693Y1472101D01*
X3093003Y1471810D01*
X3094313Y1470935D01*
G01X3124073Y1477935D02*
X3129313D01*
G01X3126693D02*
Y1460435D01*
G01X3124073D02*
X3129313D01*
G01X3137643D02*
Y1472101D01*
G01Y1468893D02*
X3138298Y1470352D01*
X3139390Y1471518D01*
X3140918Y1472101D01*
X3142446Y1471518D01*
X3143538Y1470352D01*
X3144193Y1468893D01*
Y1460435D01*
G01Y1468893D02*
X3144848Y1470352D01*
X3145939Y1471518D01*
X3147468Y1472101D01*
X3148996Y1471518D01*
X3150088Y1470352D01*
X3150743Y1468602D01*
Y1460435D01*
G01X3157763Y1454602D02*
Y1472101D01*
G01Y1469477D02*
X3158855Y1470935D01*
X3159946Y1471810D01*
X3161693Y1472101D01*
X3163221Y1471810D01*
X3164750Y1470352D01*
X3165405Y1468310D01*
X3165623Y1466268D01*
X3165405Y1464226D01*
X3164750Y1462185D01*
X3163439Y1461018D01*
X3161693Y1460435D01*
X3160165Y1460727D01*
X3158636Y1461601D01*
X3157763Y1462768D01*
G01X3175918Y1468310D02*
X3182905D01*
X3182250Y1470352D01*
X3181158Y1471518D01*
X3179630Y1472101D01*
X3178101Y1471810D01*
X3176791Y1470935D01*
X3175918Y1468893D01*
X3175481Y1467143D01*
Y1465393D01*
X3175918Y1463643D01*
X3177010Y1461893D01*
X3178320Y1460727D01*
X3179848Y1460435D01*
X3181376Y1461018D01*
X3182905Y1462768D01*
G01X3200623Y1477935D02*
Y1460435D01*
G01Y1463059D02*
X3199750Y1461601D01*
X3198439Y1460727D01*
X3196911Y1460435D01*
X3195165Y1461018D01*
X3193855Y1462476D01*
X3192981Y1464226D01*
X3192763Y1466268D01*
X3192981Y1468310D01*
X3193855Y1470060D01*
X3195165Y1471518D01*
X3196911Y1472101D01*
X3198439Y1471810D01*
X3199531Y1471226D01*
X3200623Y1470060D01*
G01X3218123Y1460435D02*
Y1472101D01*
G01Y1470060D02*
X3217250Y1471226D01*
X3215939Y1471810D01*
X3214411Y1472101D01*
X3212883Y1471518D01*
X3211573Y1470352D01*
X3210699Y1468602D01*
X3210263Y1466268D01*
X3210699Y1463935D01*
X3211573Y1462185D01*
X3212883Y1461018D01*
X3214411Y1460435D01*
X3215939Y1460727D01*
X3217250Y1461601D01*
X3218123Y1462768D01*
G01X3227981Y1460435D02*
Y1472101D01*
G01Y1469185D02*
X3228855Y1470643D01*
X3230165Y1471810D01*
X3231911Y1472101D01*
X3233439Y1471810D01*
X3234750Y1470643D01*
X3235405Y1468602D01*
Y1460435D01*
G01X3252686Y1470643D02*
X3251158Y1471810D01*
X3249848Y1472101D01*
X3248101Y1471518D01*
X3246791Y1470352D01*
X3245918Y1468310D01*
X3245699Y1466268D01*
X3245918Y1464226D01*
X3246791Y1462476D01*
X3248101Y1461018D01*
X3249848Y1460435D01*
X3251376Y1461018D01*
X3252686Y1462185D01*
G01X3263418Y1468310D02*
X3270405D01*
X3269750Y1470352D01*
X3268658Y1471518D01*
X3267130Y1472101D01*
X3265601Y1471810D01*
X3264291Y1470935D01*
X3263418Y1468893D01*
X3262981Y1467143D01*
Y1465393D01*
X3263418Y1463643D01*
X3264510Y1461893D01*
X3265820Y1460727D01*
X3267348Y1460435D01*
X3268876Y1461018D01*
X3270405Y1462768D01*
G01X0Y3937D02*
G03X3937Y0I3937J0D01*
G01X0Y3937D02*
G03X3937Y0I3937J0D01*
G01D02*
X779528D01*
G01X3937D02*
X779528D01*
G01X0Y1456693D02*
Y3937D01*
G01Y1456693D02*
Y3937D01*
G01X7874Y1460630D02*
X3937D01*
G01D02*
X7874D01*
G01X3937D02*
G03X0Y1456693I0J-3937D01*
G01X3937Y1460630D02*
G03X0Y1456693I0J-3937D01*
G01X101378Y1519685D02*
G03X97441Y1515748I0J-3937D01*
G01X101378Y1519685D02*
G03X97441Y1515748I0J-3937D01*
G01D02*
Y1509055D01*
G01Y1515748D02*
Y1509055D01*
G01X93504Y1505118D02*
X67913D01*
G01X93504D02*
G03X97441Y1509055I0J3937D01*
G01X93504Y1505118D02*
G03X97441Y1509055I0J3937D01*
G01X67913Y1505118D02*
X93504D01*
G01X63976Y1515748D02*
G03X60039Y1519685I-3937J0D01*
G01X63976Y1515748D02*
G03X60039Y1519685I-3937J0D01*
G01X63976Y1509055D02*
Y1515748D01*
G01Y1509055D02*
G03X67913Y1505118I3937J0D01*
G01X63976Y1509055D02*
G03X67913Y1505118I3937J0D01*
G01X63976Y1515748D02*
Y1509055D01*
G01X7874Y1460630D02*
G03X11811Y1464567I0J3937D01*
G01X7874Y1460630D02*
G03X11811Y1464567I0J3937D01*
G01X15748Y1519685D02*
G03X11811Y1515748I0J-3937D01*
G01X15748Y1519685D02*
G03X11811Y1515748I0J-3937D01*
G01D02*
Y1464567D01*
G01Y1515748D02*
Y1464567D01*
G01X60039Y1519685D02*
X15748D01*
G01X60039D02*
X15748D01*
G01X141181Y277843D02*
G03X148106Y264712I37662J11471D01*
G01X141181Y277843D02*
G03X148106Y264712I37662J11471D01*
G01X141181Y277843D02*
G03X121220I-9980J-3040D01*
G01X114295Y264712D02*
G03X121220Y277843I-30737J24602D01*
G01X141181D02*
G03X121220I-9980J-3040D01*
G01X114295Y264712D02*
G03X121220Y277843I-30737J24601D01*
G01X114295Y264712D02*
G03X148106I16905J-13531D01*
G01X114295D02*
G03X148106I16905J-13531D01*
G01X141181Y730599D02*
G03X148106Y717468I37662J11471D01*
G01X141181Y730599D02*
G03X148106Y717468I37662J11471D01*
G01X141181Y730599D02*
G03X121220I-9980J-3040D01*
G01X114295Y717468D02*
G03X121220Y730599I-30737J24601D01*
G01X141181D02*
G03X121220I-9980J-3040D01*
G01X114295Y717468D02*
G03X121220Y730599I-30737J24601D01*
G01X114295Y717468D02*
G03X148106I16905J-13531D01*
G01X114295D02*
G03X148106I16905J-13531D01*
G01X114295Y1170224D02*
G03X148106I16905J-13531D01*
G01X114295D02*
G03X148106I16905J-13531D01*
G01X141181Y1183355D02*
G03X148106Y1170224I37662J11471D01*
G01X141181Y1183355D02*
G03X148106Y1170224I37662J11471D01*
G01X141181Y1183355D02*
G03X121220I-9980J-3040D01*
G01X141181D02*
G03X121220I-9980J-3040D01*
G01X114295Y1170224D02*
G03X121220Y1183355I-30737J24602D01*
G01X114295Y1170224D02*
G03X121220Y1183355I-30737J24601D01*
G01X280709Y1519685D02*
X101378D01*
G01X280709D02*
X101378D01*
G01X284646Y1515748D02*
G03X280709Y1519685I-3937J0D01*
G01X284646Y1515748D02*
G03X280709Y1519685I-3937J0D01*
G01X284646Y1500000D02*
Y1515748D01*
G01Y1500000D02*
G03X288583Y1496063I3937J0D01*
G01X493307D02*
X288583D01*
G01X284646Y1500000D02*
G03X288583Y1496063I3937J0D01*
G01X493307D02*
X288583D01*
G01X284646Y1515748D02*
Y1500000D01*
G01X389213Y277843D02*
G03X369252I-9981J-3040D01*
G01X389213D02*
G03X369252I-9981J-3040D01*
G01X362327Y264712D02*
G03X369252Y277843I-30737J24602D01*
G01X362327Y264712D02*
G03X369252Y277843I-30737J24602D01*
G01X362327Y264712D02*
G03X396138I16905J-13531D01*
G01X362327D02*
G03X396138I16905J-13531D01*
G01X389213Y730599D02*
G03X369252I-9981J-3040D01*
G01X389213D02*
G03X369252I-9981J-3040D01*
G01X362327Y717468D02*
G03X369252Y730599I-30737J24602D01*
G01X362327Y717468D02*
G03X369252Y730599I-30737J24602D01*
G01X362327Y717468D02*
G03X396138I16905J-13531D01*
G01X362327D02*
G03X396138I16905J-13531D01*
G01X362327Y1170224D02*
G03X396138I16905J-13531D01*
G01X362327D02*
G03X396138I16905J-13531D01*
G01X389213Y1183355D02*
G03X369252I-9981J-3040D01*
G01X389213D02*
G03X369252I-9981J-3040D01*
G01X362327Y1170224D02*
G03X369252Y1183355I-30737J24602D01*
G01X362327Y1170224D02*
G03X369252Y1183355I-30737J24602D01*
G01X322441Y1503937D02*
G03Y1496063I0J-3937D01*
G01X459449Y1503937D02*
X322441D01*
G01X459449D02*
X322441D01*
G01D02*
G03Y1496063I0J-3937D01*
G01X296457Y1519685D02*
G03X292520Y1515748I0J-3937D01*
G01X296457Y1519685D02*
X485433D01*
G01X296457D02*
G03X292520Y1515748I0J-3937D01*
G01X296457Y1519685D02*
X485433D01*
G01X304331Y1503937D02*
X292520D01*
G01Y1515748D02*
Y1503937D01*
G01X304331D02*
X292520D01*
G01Y1515748D02*
Y1503937D01*
G01X304331Y1496063D02*
G03Y1503937I0J3937D01*
G01Y1496063D02*
G03Y1503937I0J3937D01*
G01X389213Y277843D02*
G03X396138Y264712I37662J11471D01*
G01X389213Y277843D02*
G03X396138Y264712I37662J11470D01*
G01X389213Y730599D02*
G03X396138Y717468I37662J11471D01*
G01X389213Y730599D02*
G03X396138Y717468I37662J11470D01*
G01X389213Y1183355D02*
G03X396138Y1170224I37662J11471D01*
G01X389213Y1183355D02*
G03X396138Y1170224I37662J11470D01*
G01X477559Y1503937D02*
G03Y1496063I0J-3937D01*
G01X459449D02*
G03Y1503937I0J3937D01*
G01X489370D02*
X477559D01*
G01D02*
G03Y1496063I0J-3937D01*
G01X459449D02*
G03Y1503937I0J3937D01*
G01X489370D02*
X477559D01*
G01X489370Y1515748D02*
G03X485433Y1519685I-3937J0D01*
G01X489370Y1515748D02*
G03X485433Y1519685I-3937J0D01*
G01X501181D02*
G03X497244Y1515748I0J-3937D01*
G01X680512Y1519685D02*
X501181D01*
G01D02*
G03X497244Y1515748I0J-3937D01*
G01X680512Y1519685D02*
X501181D01*
G01X489370Y1515748D02*
Y1503937D01*
G01X493307Y1496063D02*
G03X497244Y1500000I0J3937D01*
G01Y1515748D02*
Y1500000D01*
G01X489370Y1515748D02*
Y1503937D01*
G01X493307Y1496063D02*
G03X497244Y1500000I0J3937D01*
G01Y1515748D02*
Y1500000D01*
G01X637244Y277843D02*
G03X644169Y264712I37662J11471D01*
G01X637244Y277843D02*
G03X644169Y264712I37662J11471D01*
G01X637244Y277843D02*
G03X617283I-9980J-3040D01*
G01X610358Y264712D02*
G03X617283Y277843I-30737J24602D01*
G01X637244D02*
G03X617283I-9980J-3040D01*
G01X610358Y264712D02*
G03X617283Y277843I-30737J24601D01*
G01X610358Y264712D02*
G03X644169I16906J-13531D01*
G01X610358D02*
G03X644169I16906J-13531D01*
G01X637244Y730599D02*
G03X644169Y717468I37662J11471D01*
G01X637244Y730599D02*
G03X644169Y717468I37662J11471D01*
G01X637244Y730599D02*
G03X617283I-9980J-3040D01*
G01X610358Y717468D02*
G03X617283Y730599I-30737J24601D01*
G01X637244D02*
G03X617283I-9980J-3040D01*
G01X610358Y717468D02*
G03X617283Y730599I-30737J24601D01*
G01X610358Y717468D02*
G03X644169I16906J-13531D01*
G01X610358D02*
G03X644169I16906J-13531D01*
G01X610358Y1170224D02*
G03X644169I16906J-13531D01*
G01X610358D02*
G03X644169I16906J-13531D01*
G01X637244Y1183355D02*
G03X644169Y1170224I37662J11471D01*
G01X637244Y1183355D02*
G03X644169Y1170224I37662J11471D01*
G01X637244Y1183355D02*
G03X617283I-9980J-3040D01*
G01X637244D02*
G03X617283I-9980J-3040D01*
G01X610358Y1170224D02*
G03X617283Y1183355I-30737J24602D01*
G01X610358Y1170224D02*
G03X617283Y1183355I-30737J24601D01*
G01X730339Y383610D02*
G03X764149I16905J-13531D01*
G01X730339Y383609D02*
G03X764150I16905J-13530D01*
G01X757225Y396741D02*
G03X764149Y383610I37663J11469D01*
G01X757224Y396741D02*
G03X764150Y383609I37662J11471D01*
G01X757225Y396741D02*
G03X737264I-9981J-3040D01*
G01X730339Y383610D02*
G03X737264Y396741I-30737J24602D01*
G01X757224D02*
G03X737264I-9980J-3041D01*
G01X730339Y383609D02*
G03X737264Y396741I-30738J24601D01*
G01X757225Y829811D02*
G03X764149Y816680I37663J11469D01*
G01X757224Y829811D02*
G03X764150Y816680I37662J11473D01*
G01X757225Y829811D02*
G03X737264I-9981J-3039D01*
G01X757224D02*
G03X737264I-9980J-3040D01*
G01X730339Y816680D02*
G03X737264Y829811I-30737J24602D01*
G01X730339Y816680D02*
G03X737264Y829811I-30737J24602D01*
G01X730339Y816680D02*
G03X764149I16905J-13531D01*
G01X730339D02*
G03X764150I16905J-13531D01*
G01X721850Y1519685D02*
G03X717913Y1515748I0J-3937D01*
G01X775591Y1519685D02*
X721850D01*
G01D02*
G03X717913Y1515748I0J-3937D01*
G01X775591Y1519685D02*
X721850D01*
G01X713976Y1505118D02*
G03X717913Y1509055I0J3937D01*
G01Y1515748D02*
Y1509055D01*
G01X713976Y1505118D02*
G03X717913Y1509055I0J3937D01*
G01Y1515748D02*
Y1509055D01*
G01X684449Y1515748D02*
G03X680512Y1519685I-3937J0D01*
G01X684449Y1515748D02*
G03X680512Y1519685I-3937J0D01*
G01X684449Y1509055D02*
Y1515748D01*
G01Y1509055D02*
G03X688386Y1505118I3937J0D01*
G01X713976D02*
X688386D01*
G01X684449Y1509055D02*
G03X688386Y1505118I3937J0D01*
G01D02*
X713976D01*
G01X684449Y1515748D02*
Y1509055D01*
G01X791339Y3937D02*
G03X795276Y0I3937J0D01*
G01D02*
X892317D01*
G01X791339Y3937D02*
Y23622D01*
G01Y3937D02*
G03X795276Y0I3937J0D01*
G01X791339Y3937D02*
Y23622D01*
G01X795276Y0D02*
X892317D01*
G01X783465Y54331D02*
G03X791339I3937J0D01*
G01X783465D02*
G03X791339I3937J0D01*
G01Y23622D02*
G03X783465I-3937J0D01*
G01X791339D02*
G03X783465I-3937J0D01*
G01X779528Y0D02*
G03X783465Y3937I0J3937D01*
G01X779528Y0D02*
G03X783465Y3937I0J3937D01*
G01X791339Y54331D02*
Y181890D01*
G01Y54331D02*
Y181890D01*
G01X783465Y3937D02*
Y185827D01*
G01Y3937D02*
Y185827D01*
G01X811024Y181890D02*
G03X822835Y193701I0J11811D01*
G01X791339Y181890D02*
X811024D01*
G01D02*
G03X822835Y193701I0J11811D01*
G01X791339Y181890D02*
X811024D01*
G01X787402Y189764D02*
G03X783465Y185827I0J-3937D01*
G01X787402Y189764D02*
G03X783465Y185827I0J-3937D01*
G01X811024Y189764D02*
G03X814961Y193701I0J3937D01*
G01X787402Y189764D02*
X811024D01*
G01D02*
G03X814961Y193701I0J3937D01*
G01X787402Y189764D02*
X811024D01*
G01X822835Y193701D02*
Y240157D01*
G01Y193701D02*
Y240157D01*
G01X814961Y193701D02*
Y244094D01*
G01Y193701D02*
Y244094D01*
G01X818898Y248031D02*
G03X814961Y244094I0J-3937D01*
G01X818898Y248031D02*
G03X814961Y244094I0J-3937D01*
G01X928098Y240157D02*
X822835D01*
G01X928098D02*
X822835D01*
G01X818898Y248031D02*
X1055118D01*
G01D02*
X818898D01*
G01X954331Y1503937D02*
X817323D01*
G01X954331D02*
X817323D01*
G01X791339Y1519685D02*
G03X787402Y1515748I0J-3937D01*
G01X791339Y1519685D02*
X980315D01*
G01X791339D02*
G03X787402Y1515748I0J-3937D01*
G01X791339Y1519685D02*
X980315D01*
G01X817323Y1503937D02*
G03Y1496063I0J-3937D01*
G01X799213D02*
G03Y1503937I0J3937D01*
G01D02*
X787402D01*
G01Y1515748D02*
Y1503937D01*
G01X799213D02*
X787402D01*
G01X817323D02*
G03Y1496063I0J-3937D01*
G01X799213D02*
G03Y1503937I0J3937D01*
G01X787402Y1515748D02*
Y1503937D01*
G01X779528Y1515748D02*
G03X775591Y1519685I-3937J0D01*
G01X779528Y1515748D02*
G03X775591Y1519685I-3937J0D01*
G01X779528Y1500000D02*
Y1515748D01*
G01Y1500000D02*
G03X783465Y1496063I3937J0D01*
G01X988189D02*
X783465D01*
G01X779528Y1500000D02*
G03X783465Y1496063I3937J0D01*
G01X988189D02*
X783465D01*
G01X779528Y1515748D02*
Y1500000D01*
G01X900191Y0D02*
G03X892317I-3937J0D01*
G01X896254D02*
Y-394D01*
G01Y0D02*
Y394D01*
G01X895762Y0D02*
X896746D01*
G01X900191D02*
G03X892317I-3937J0D01*
G01X900191D02*
X1212598D01*
G01X900191D02*
X1212598D01*
G01X953294Y248031D02*
G03Y240157I1J-3937D01*
G01X1051181D02*
X953294D01*
G01Y248031D02*
G03Y240157I1J-3937D01*
G01X928098D02*
G03Y248031I0J3937D01*
G01Y240157D02*
G03Y248031I0J3937D01*
G01X1051181Y240157D02*
X953294D01*
G01X971398Y718788D02*
G03X951437I-9980J-3040D01*
G01X944512Y705657D02*
G03X951437Y718788I-30737J24602D01*
G01X971398D02*
G03X951437I-9980J-3040D01*
G01X944512Y705657D02*
G03X951437Y718788I-30737J24602D01*
G01X944512Y705657D02*
G03X978323I16905J-13531D01*
G01X944512D02*
G03X978323I16905J-13531D01*
G01X944512Y974161D02*
G03X978323I16905J-13531D01*
G01X944512D02*
G03X978323I16905J-13531D01*
G01X971398Y987292D02*
G03X951437I-9980J-3040D01*
G01X944512Y974161D02*
G03X951437Y987292I-30737J24602D01*
G01X971398D02*
G03X951437I-9980J-3040D01*
G01X944512Y974161D02*
G03X951437Y987292I-30737J24602D01*
G01X954331Y1496063D02*
G03Y1503937I0J3937D01*
G01Y1496063D02*
G03Y1503937I0J3937D01*
G01X1051181Y193701D02*
G03X1062992Y181890I11811J0D01*
G01X1051181Y193701D02*
G03X1062992Y181890I11811J0D01*
G01X1051181Y240157D02*
Y193701D01*
G01Y240157D02*
Y193701D01*
G01X971398Y718788D02*
G03X978323Y705657I37662J11471D01*
G01X971398Y718788D02*
G03X978323Y705657I37662J11470D01*
G01X971398Y987292D02*
G03X978323Y974161I37662J11471D01*
G01X971398Y987292D02*
G03X978323Y974161I37662J11470D01*
G01X1059196Y1519685D02*
X996063D01*
G01X1059196D02*
X996063D01*
G01X984252Y1515748D02*
G03X980315Y1519685I-3937J0D01*
G01X984252Y1515748D02*
G03X980315Y1519685I-3937J0D01*
G01X996063D02*
G03X992126Y1515748I0J-3937D01*
G01X996063Y1519685D02*
G03X992126Y1515748I0J-3937D01*
G01X972441Y1503937D02*
G03Y1496063I0J-3937D01*
G01X984252Y1503937D02*
X972441D01*
G01X984252Y1515748D02*
Y1503937D01*
G01X972441D02*
G03Y1496063I0J-3937D01*
G01X988189D02*
G03X992126Y1500000I0J3937D01*
G01Y1515748D02*
Y1500000D01*
G01X984252Y1515748D02*
Y1503937D01*
G01D02*
X972441D01*
G01X988189Y1496063D02*
G03X992126Y1500000I0J3937D01*
G01Y1515748D02*
Y1500000D01*
G01X1133071Y189764D02*
G03Y181890I0J-3937D01*
G01D02*
X1216535D01*
G01X1133071D02*
X1216535D01*
G01X1133071Y189764D02*
G03Y181890I0J-3937D01*
G01X1102362D02*
G03Y189764I0J3937D01*
G01Y181890D02*
G03Y189764I0J3937D01*
G01X1062992Y181890D02*
X1102362D01*
G01X1062992D02*
X1102362D01*
G01X1059055Y244094D02*
G03X1055118Y248031I-3937J0D01*
G01X1059055Y244094D02*
G03X1055118Y248031I-3937J0D01*
G01X1059055Y244094D02*
Y193701D01*
G01Y244094D02*
Y193701D01*
G01X1062992Y189764D02*
X1220472D01*
G01X1059055Y193701D02*
G03X1062992Y189764I3937J0D01*
G01X1059055Y193701D02*
G03X1062992Y189764I3937J0D01*
G01D02*
X1220472D01*
G01X1085630Y1417323D02*
G03X1089567Y1421260I0J3937D01*
G01X1085630Y1417323D02*
G03X1089567Y1421260I0J3937D01*
G01X1072638D02*
G03X1076575Y1417322I3937J-1D01*
G01X1085630Y1417323D02*
X1076575D01*
G01X1072638Y1421260D02*
G03X1076575Y1417323I3937J0D01*
G01D02*
X1085630D01*
G01X1089567Y1506243D02*
Y1421260D01*
G01Y1506243D02*
Y1421260D01*
G01X1072638D02*
Y1506243D01*
G01D02*
Y1421260D01*
G01X1103009Y1519685D02*
G03X1100225Y1518532I0J-3937D01*
G01X1207283Y1519685D02*
X1103009D01*
G01D02*
G03X1100225Y1518532I0J-3937D01*
G01X1207283Y1519685D02*
X1103009D01*
G01X1090720Y1509027D02*
G03X1089567Y1506243I2784J-2784D01*
G01X1100225Y1518532D02*
X1090720Y1509027D01*
G01D02*
G03X1089567Y1506243I2784J-2784D01*
G01X1100225Y1518532D02*
X1090720Y1509027D01*
G01X1061980Y1518532D02*
G03X1059196Y1519685I-2784J-2784D01*
G01X1061980Y1518532D02*
G03X1059196Y1519685I-2784J-2784D01*
G01X1071485Y1509027D02*
X1061980Y1518532D01*
G01X1072638Y1506243D02*
G03X1071485Y1509027I-3937J0D01*
G01X1072638Y1506243D02*
G03X1071485Y1509027I-3937J0D01*
G01X1061980Y1518532D02*
X1071485Y1509027D01*
G01X1216535Y54331D02*
G03X1224409I3937J0D01*
G01X1216535D02*
Y181890D01*
G01Y54331D02*
Y181890D01*
G01Y54331D02*
G03X1224409I3937J0D01*
G01Y23622D02*
G03X1216535I-3937J0D01*
G01X1224409D02*
G03X1216535I-3937J0D01*
G01X1212598Y0D02*
G03X1216535Y3937I0J3937D01*
G01D02*
Y23622D01*
G01X1212598Y0D02*
G03X1216535Y3937I0J3937D01*
G01X1224409D02*
G03X1228346Y0I3937J0D01*
G01X1224409Y185827D02*
Y3937D01*
G01X1216535D02*
Y23622D01*
G01X1224409Y3937D02*
G03X1228346Y0I3937J0D01*
G01X1224409Y3937D02*
Y185827D01*
G01X1228346Y0D02*
X1930906D01*
G01X1228346D02*
X1930906D01*
G01X1224409Y185827D02*
G03X1220472Y189764I-3937J0D01*
G01X1224409Y185827D02*
G03X1220472Y189764I-3937J0D01*
G01X1164984Y383609D02*
G03X1198795I16906J-13530D01*
G01X1164984D02*
G03X1198795I16906J-13530D01*
G01X1191870Y396741D02*
G03X1198795Y383610I37662J11471D01*
G01X1191870Y396741D02*
G03X1198795Y383609I37663J11469D01*
G01X1191870Y396741D02*
G03X1171909I-9980J-3040D01*
G01X1164984Y383610D02*
G03X1171909Y396741I-30737J24602D01*
G01X1191870D02*
G03X1171909I-9980J-3040D01*
G01X1164984Y383609D02*
G03X1171909Y396741I-30737J24601D01*
G01X1164984Y974161D02*
G03X1198795I16906J-13531D01*
G01X1164984D02*
G03X1198795I16906J-13531D01*
G01X1191870Y987292D02*
G03X1198795Y974161I37662J11471D01*
G01X1191870Y987292D02*
G03X1198795Y974161I37662J11471D01*
G01X1191870Y987292D02*
G03X1171909I-9980J-3040D01*
G01X1164984Y974161D02*
G03X1171909Y987292I-30737J24602D01*
G01X1191870D02*
G03X1171909I-9980J-3040D01*
G01X1164984Y974161D02*
G03X1171909Y987292I-30737J24601D01*
G01X1240748Y1505118D02*
G03X1244685Y1509055I0J3937D01*
G01X1240748Y1505118D02*
G03X1244685Y1509055I0J3937D01*
G01X1211220Y1515748D02*
G03X1207283Y1519685I-3937J0D01*
G01X1211220Y1515748D02*
G03X1207283Y1519685I-3937J0D01*
G01X1211220Y1509055D02*
Y1515748D01*
G01Y1509055D02*
G03X1215157Y1505118I3937J0D01*
G01X1240748D02*
X1215157D01*
G01X1211220Y1509055D02*
G03X1215157Y1505118I3937J0D01*
G01D02*
X1240748D01*
G01X1211220Y1515748D02*
Y1509055D01*
G01X1311851Y277843D02*
G03X1318775Y264712I37663J11469D01*
G01X1311850Y277843D02*
G03X1318776Y264712I37661J11473D01*
G01X1311851Y277843D02*
G03X1291890I-9980J-3040D01*
G01X1284965Y264712D02*
G03X1291890Y277843I-30737J24602D01*
G01X1311850D02*
G03X1291890I-9980J-3040D01*
G01X1284965Y264712D02*
G03X1291890Y277843I-30737J24602D01*
G01X1284965Y264712D02*
G03X1318775I16905J-13531D01*
G01X1284965D02*
G03X1318776I16906J-13531D01*
G01X1311851Y730599D02*
G03X1318775Y717468I37663J11469D01*
G01X1311850Y730599D02*
G03X1318776Y717468I37661J11473D01*
G01X1311851Y730599D02*
G03X1291890I-9980J-3040D01*
G01X1284965Y717468D02*
G03X1291891Y730599I-30736J24604D01*
G01X1311850D02*
G03X1291890I-9980J-3040D01*
G01X1284965Y717468D02*
G03X1291890Y730599I-30737J24602D01*
G01X1284965Y717468D02*
G03X1318775I16905J-13531D01*
G01X1284965D02*
G03X1318776I16906J-13531D01*
G01X1284965Y1170224D02*
G03X1318775I16905J-13531D01*
G01X1284965D02*
G03X1318776I16906J-13531D01*
G01X1311851Y1183355D02*
G03X1318775Y1170224I37663J11469D01*
G01X1311850Y1183355D02*
G03X1318776Y1170224I37661J11473D01*
G01X1311851Y1183355D02*
G03X1291890I-9980J-3040D01*
G01X1311850D02*
G03X1291890I-9980J-3040D01*
G01X1284965Y1170224D02*
G03X1291890Y1183355I-30737J24602D01*
G01X1284965Y1170224D02*
G03X1291890Y1183355I-30737J24602D01*
G01X1248622Y1519685D02*
G03X1244685Y1515748I0J-3937D01*
G01X1427953Y1519685D02*
X1248622D01*
G01D02*
G03X1244685Y1515748I0J-3937D01*
G01X1427953Y1519685D02*
X1248622D01*
G01X1244685Y1515748D02*
Y1509055D01*
G01Y1515748D02*
Y1509055D01*
G01X1431890Y1515748D02*
G03X1427953Y1519685I-3937J0D01*
G01X1431890Y1515748D02*
G03X1427953Y1519685I-3937J0D01*
G01X1431890Y1500000D02*
Y1515748D01*
G01Y1500000D02*
G03X1435827Y1496063I3937J0D01*
G01X1431890Y1500000D02*
G03X1435827Y1496063I3937J0D01*
G01X1431890Y1515748D02*
Y1500000D01*
G01X1532996Y264712D02*
G03X1566807I16906J-13531D01*
G01X1532996D02*
G03X1566807I16906J-13531D01*
G01X1532996Y717468D02*
G03X1566807I16906J-13531D01*
G01X1532996D02*
G03X1566807I16906J-13531D01*
G01X1532996Y1170224D02*
G03X1566807I16906J-13531D01*
G01X1532996D02*
G03X1566807I16906J-13531D01*
G01X1469685Y1503937D02*
G03Y1496063I0J-3937D01*
G01X1451575D02*
G03Y1503937I0J3937D01*
G01X1606693D02*
X1469685D01*
G01X1606693D02*
X1469685D01*
G01D02*
G03Y1496063I0J-3937D01*
G01X1451575D02*
G03Y1503937I0J3937D01*
G01X1443701Y1519685D02*
G03X1439764Y1515748I0J-3937D01*
G01X1443701Y1519685D02*
X1632677D01*
G01X1443701D02*
G03X1439764Y1515748I0J-3937D01*
G01X1443701Y1519685D02*
X1632677D01*
G01X1451575Y1503937D02*
X1439764D01*
G01Y1515748D02*
Y1503937D01*
G01X1451575D02*
X1439764D01*
G01X1640551Y1496063D02*
X1435827D01*
G01X1439764Y1515748D02*
Y1503937D01*
G01X1640551Y1496063D02*
X1435827D01*
G01X1559882Y277843D02*
G03X1566807Y264712I37662J11471D01*
G01X1559882Y277843D02*
G03X1539921I-9980J-3040D01*
G01X1559882D02*
G03X1566807Y264712I37662J11471D01*
G01X1559882Y277843D02*
G03X1539921I-9980J-3040D01*
G01X1532996Y264712D02*
G03X1539921Y277843I-30737J24602D01*
G01X1532996Y264712D02*
G03X1539921Y277843I-30737J24602D01*
G01X1559882Y730599D02*
G03X1566807Y717468I37662J11471D01*
G01X1559882Y730599D02*
G03X1539921I-9980J-3040D01*
G01X1559882D02*
G03X1566807Y717468I37662J11471D01*
G01X1559882Y730599D02*
G03X1539921I-9980J-3040D01*
G01X1532996Y717468D02*
G03X1539921Y730599I-30737J24601D01*
G01X1532996Y717468D02*
G03X1539921Y730599I-30737J24601D01*
G01X1559882Y1183355D02*
G03X1539921I-9980J-3040D01*
G01X1559882D02*
G03X1539921I-9980J-3040D01*
G01X1559882D02*
G03X1566807Y1170224I37662J11471D01*
G01X1559882Y1183355D02*
G03X1566807Y1170224I37662J11471D01*
G01X1532996D02*
G03X1539921Y1183355I-30737J24602D01*
G01X1532996Y1170224D02*
G03X1539921Y1183355I-30737J24601D01*
G01X1636614Y1503937D02*
X1624803D01*
G01X1636614D02*
X1624803D01*
G01D02*
G03Y1496063I0J-3937D01*
G01X1606693D02*
G03Y1503937I0J3937D01*
G01X1624803D02*
G03Y1496063I0J-3937D01*
G01X1606693D02*
G03Y1503937I0J3937D01*
G01X1636614Y1515748D02*
G03X1632677Y1519685I-3937J0D01*
G01X1636614Y1515748D02*
G03X1632677Y1519685I-3937J0D01*
G01X1648425D02*
G03X1644488Y1515748I0J-3937D01*
G01X1827756Y1519685D02*
X1648425D01*
G01D02*
G03X1644488Y1515748I0J-3937D01*
G01X1827756Y1519685D02*
X1648425D01*
G01X1636614Y1515748D02*
Y1503937D01*
G01X1640551Y1496063D02*
G03X1644488Y1500000I0J3937D01*
G01Y1515748D02*
Y1500000D01*
G01X1636614Y1515748D02*
Y1503937D01*
G01X1640551Y1496063D02*
G03X1644488Y1500000I0J3937D01*
G01Y1515748D02*
Y1500000D01*
G01X1807914Y277843D02*
G03X1814838Y264712I37663J11469D01*
G01X1807913Y277843D02*
G03X1814839Y264712I37661J11473D01*
G01X1807914Y277843D02*
G03X1787953I-9980J-3040D01*
G01X1781028Y264712D02*
G03X1787953Y277843I-30737J24602D01*
G01X1807913D02*
G03X1787953I-9980J-3040D01*
G01X1781028Y264712D02*
G03X1787953Y277843I-30737J24602D01*
G01X1781028Y264712D02*
G03X1814839I16906J-13531D01*
G01X1781028D02*
G03X1814839I16906J-13531D01*
G01X1807914Y730599D02*
G03X1814838Y717468I37663J11469D01*
G01X1807913Y730599D02*
G03X1814839Y717468I37661J11473D01*
G01X1807914Y730599D02*
G03X1787953I-9980J-3040D01*
G01X1781028Y717468D02*
G03X1787954Y730599I-30736J24604D01*
G01X1807913D02*
G03X1787953I-9980J-3040D01*
G01X1781028Y717468D02*
G03X1787953Y730599I-30737J24602D01*
G01X1781028Y717468D02*
G03X1814838I16905J-13531D01*
G01X1781028D02*
G03X1814839I16906J-13531D01*
G01X1781028Y1170224D02*
G03X1814838I16905J-13531D01*
G01X1781028D02*
G03X1814839I16906J-13531D01*
G01X1807914Y1183355D02*
G03X1814838Y1170224I37662J11468D01*
G01X1807913Y1183355D02*
G03X1814839Y1170224I37661J11473D01*
G01X1807914Y1183355D02*
G03X1787953I-9980J-3040D01*
G01X1807913D02*
G03X1787953I-9980J-3040D01*
G01X1781028Y1170224D02*
G03X1787953Y1183355I-30737J24602D01*
G01X1781028Y1170224D02*
G03X1787953Y1183355I-30737J24602D01*
G01X1869094Y1519685D02*
G03X1865157Y1515748I0J-3937D01*
G01X1919094Y1519685D02*
X1869094D01*
G01D02*
G03X1865157Y1515748I0J-3937D01*
G01X1919094Y1519685D02*
X1869094D01*
G01X1865157Y1515748D02*
Y1509055D01*
G01Y1515748D02*
Y1509055D01*
G01X1861220Y1505118D02*
X1835630D01*
G01X1861220D02*
G03X1865157Y1509055I0J3937D01*
G01X1861220Y1505118D02*
G03X1865157Y1509055I0J3937D01*
G01X1835630Y1505118D02*
X1861220D01*
G01X1831693Y1515748D02*
G03X1827756Y1519685I-3937J0D01*
G01X1831693Y1515748D02*
G03X1827756Y1519685I-3937J0D01*
G01X1831693Y1509055D02*
Y1515748D01*
G01Y1509055D02*
G03X1835630Y1505118I3937J0D01*
G01X1831693Y1509055D02*
G03X1835630Y1505118I3937J0D01*
G01X1831693Y1515748D02*
Y1509055D01*
G01X1930906Y0D02*
G03X1934843Y3937I0J3937D01*
G01X1930906Y0D02*
G03X1934843Y3937I0J3937D01*
G01D02*
Y1456693D01*
G01Y3937D02*
Y1456693D01*
G01X1930906Y1460630D02*
X1926969D01*
G01X1934843Y1456693D02*
G03X1930906Y1460630I-3937J0D01*
G01X1934843Y1456693D02*
G03X1930906Y1460630I-3937J0D01*
G01D02*
X1926969D01*
G01X1923031Y1515748D02*
G03X1919094Y1519685I-3937J0D01*
G01X1923031Y1515748D02*
G03X1919094Y1519685I-3937J0D01*
G01X1923031Y1464567D02*
Y1515748D01*
G01Y1464567D02*
G03X1926969Y1460630I3937J0D01*
G01X1923031Y1464567D02*
G03X1926969Y1460630I3937J0D01*
G01X1923031Y1515748D02*
Y1464567D01*
G54D12*
G01X95800Y62800D02*
X171512Y138512D01*
G01X92500Y62800D02*
X95800D01*
G01X58709Y372346D02*
X73826Y387463D01*
G01D02*
X213597D01*
G01X106322Y529322D02*
X93800Y516800D01*
G01X95500Y967980D02*
Y968000D01*
G01X118110Y945370D02*
X95500Y967980D01*
G01X171512Y141323D02*
X209559Y179370D01*
G01X171512Y138512D02*
Y141323D01*
G01X192842Y372000D02*
X203080D01*
G01X106322Y532129D02*
Y529322D01*
G01X110708Y536515D02*
X106322Y532129D01*
G01X119179Y536515D02*
X110708D01*
G01X171512Y588848D02*
X119179Y536515D01*
G01X171512Y593823D02*
Y588848D01*
G01X208913Y631224D02*
X171512Y593823D01*
G01X211160Y945370D02*
X118110D01*
G01X183500Y1224500D02*
X677700D01*
G01X133862Y1274138D02*
X183500Y1224500D01*
G01X133862Y1412612D02*
Y1274138D01*
G01X121274Y1425200D02*
X133862Y1412612D01*
G01X121274Y1439000D02*
Y1425200D01*
G01X124874Y1442600D02*
X121274Y1439000D01*
G01X220641Y80500D02*
X317786Y177645D01*
G01X220000Y80500D02*
X220641D01*
G01X209559Y179370D02*
X625171D01*
G01X203080Y372000D02*
X234190Y403110D01*
G01X283200Y410575D02*
X686275D01*
G01X275735Y403110D02*
X283200Y410575D01*
G01X234190Y403110D02*
X275735D01*
G01X280800Y412302D02*
X685002D01*
G01X274331Y405833D02*
X280800Y412302D01*
G01X231967Y405833D02*
X274331D01*
G01X213597Y387463D02*
X231967Y405833D01*
G01X220985Y516600D02*
X218000D01*
G01X296012Y591627D02*
X220985Y516600D01*
G01X330773Y631224D02*
X208913D01*
G01X228924Y927606D02*
X211160Y945370D01*
G01X559258Y927606D02*
X228924D01*
G01X257076Y929496D02*
X561368D01*
G01X218100Y968472D02*
X257076Y929496D01*
G01X218100Y969700D02*
Y968472D01*
G01X353280Y78249D02*
X450691Y175660D01*
G01X353280Y71780D02*
Y78249D01*
G01X345200Y63700D02*
X353280Y71780D01*
G01X341800Y63700D02*
X345200D01*
G01X317786Y177645D02*
X625886D01*
G01X308621Y372300D02*
X345171Y408850D01*
G01X294542Y372300D02*
X308621D01*
G01X345171Y408850D02*
X687560D01*
G01X345398Y516800D02*
X341800D01*
G01X418191Y589593D02*
X345398Y516800D01*
G01X330924Y631375D02*
X330773Y631224D01*
G01X609103Y631375D02*
X330924D01*
G01X296012Y593823D02*
Y591627D01*
G01X330089Y627900D02*
X296012Y593823D01*
G01X608068Y627900D02*
X330089D01*
G01X380079Y931221D02*
X563643D01*
G01X341900Y969400D02*
X380079Y931221D01*
G01X470250Y80500D02*
X468500D01*
G01X563568Y173818D02*
X470250Y80500D01*
G01X450691Y175660D02*
X626341D01*
G01X430610Y372000D02*
X465735Y407125D01*
G01X419042Y372000D02*
X430610D01*
G01X465735Y407125D02*
X688275D01*
G01X467013Y516900D02*
X466000D01*
G01X472863Y522750D02*
X467013Y516900D01*
G01X472863Y534213D02*
Y522750D01*
G01X478301Y539651D02*
X472863Y534213D01*
G01X534551Y539651D02*
X478301D01*
G01X418191Y596744D02*
Y589593D01*
G01X446527Y625080D02*
X418191Y596744D01*
G01X611320Y625080D02*
X446527D01*
G01X466100Y969200D02*
X502354Y932946D01*
G01X626939Y173818D02*
X563568D01*
G01X556087Y372300D02*
X589187Y405400D01*
G01X543242Y372300D02*
X556087D01*
G01X695874Y700974D02*
X534551Y539651D01*
G01X582167Y637413D02*
X516000D01*
G01X585904Y900960D02*
X559258Y927606D01*
G01X561368Y929496D02*
X589904Y900960D01*
G01X565918Y932946D02*
X597904Y900960D01*
G01X502354Y932946D02*
X565918D01*
G01X563643Y931221D02*
X593904Y900960D01*
G01X596502Y70202D02*
X590600Y64300D01*
G01X596502Y73123D02*
Y70202D01*
G01X661703Y138324D02*
X596502Y73123D01*
G01X626341Y175660D02*
X780216Y329535D01*
G01X625886Y177645D02*
X778231Y329990D01*
G01X625171Y179370D02*
X776506Y330705D01*
G01X661703Y202190D02*
Y138324D01*
G01X781941Y328820D02*
X626939Y173818D01*
G01X786100Y326587D02*
X661703Y202190D01*
G01X654242Y372000D02*
Y381037D01*
G01D02*
X676880Y403675D01*
G01X589187Y405400D02*
X690310D01*
G01X668512Y516488D02*
X673900Y511100D01*
G01X668512Y628612D02*
Y516488D01*
G01X601500Y531000D02*
X657300Y586800D01*
G01X601500Y515700D02*
Y531000D01*
G01X590400Y504600D02*
X601500Y515700D01*
G01X583550Y504600D02*
X590400D01*
G01X709500Y669600D02*
X668512Y628612D01*
G01X604094Y659340D02*
X582167Y637413D01*
G01X634628Y659340D02*
X604094D01*
G01X682575Y707287D02*
X634628Y659340D01*
G01X684300Y706572D02*
X609103Y631375D01*
G01X692700Y706460D02*
X611320Y625080D01*
G01X666900Y648000D02*
Y665400D01*
G01X657300Y638400D02*
X666900Y648000D01*
G01X657300Y586800D02*
Y638400D01*
G01X688800Y708632D02*
X608068Y627900D01*
G01X594390Y908474D02*
X601904Y900960D01*
G01X594390Y965310D02*
Y908474D01*
G01X590200Y969500D02*
X594390Y965310D01*
G01X712214Y82500D02*
Y95175D01*
G01X722205Y134077D02*
Y258049D01*
G01X717000Y128872D02*
X722205Y134077D01*
G01X717000Y99961D02*
Y128872D01*
G01X712214Y95175D02*
X717000Y99961D01*
G01X722205Y258049D02*
X788801Y324645D01*
G01X724820Y446110D02*
X770798D01*
G01X687560Y408850D02*
X724820Y446110D01*
G01X722400Y435050D02*
X769300D01*
G01X691025Y403675D02*
X722400Y435050D01*
G01X676880Y403675D02*
X691025D01*
G01X723640Y447940D02*
X769582D01*
G01X686275Y410575D02*
X723640Y447940D01*
G01X724930Y443780D02*
X771159D01*
G01X688275Y407125D02*
X724930Y443780D01*
G01X722365Y449665D02*
X768850D01*
G01X685002Y412302D02*
X722365Y449665D01*
G01X725205Y440295D02*
X770545D01*
G01X690310Y405400D02*
X725205Y440295D01*
G01X760200Y553975D02*
Y658980D01*
G01X797690Y516485D02*
X760200Y553975D01*
G01X673900Y511100D02*
X698600D01*
G01X757025Y554344D02*
Y659715D01*
G01X795706Y515663D02*
X757025Y554344D01*
G01X755300Y553629D02*
Y659000D01*
G01X793981Y514948D02*
X755300Y553629D01*
G01X764925Y554435D02*
X802185Y517175D01*
G01X764925Y659135D02*
Y554435D01*
G01X763200Y553415D02*
X800244Y516371D01*
G01X763200Y658420D02*
Y553415D01*
G01X760200Y658980D02*
X723000Y696180D01*
G01X757025Y659715D02*
X720600Y696140D01*
G01X755300Y659000D02*
X718100Y696200D01*
G01X727800Y696260D02*
X764925Y659135D01*
G01X724988Y696632D02*
X763200Y658420D01*
G01X723000Y696180D02*
Y739200D01*
G01X768000Y705600D02*
X728100Y745500D01*
G01X709500Y685875D02*
Y669600D01*
G01X709871Y686246D02*
X709500Y685875D01*
G01X741800Y755500D02*
X712400Y784900D01*
G01X777300Y755500D02*
X741800D01*
G01X720600Y741600D02*
X718200Y744000D01*
G01X720600Y696140D02*
Y741600D01*
G01X682575Y840125D02*
Y707287D01*
G01X684300Y839410D02*
Y706572D01*
G01X692700Y839968D02*
Y706460D01*
G01X718100Y696200D02*
Y738500D01*
G01X727800Y740925D02*
Y696260D01*
G01X728175Y741300D02*
X727800Y740925D01*
G01X724988Y742012D02*
Y696632D01*
G01X723300Y743700D02*
X724988Y742012D01*
G01X688800Y839500D02*
Y708632D01*
G01X695874Y840702D02*
Y700974D01*
G01X712400Y835361D02*
X753039Y876000D01*
G01X712400Y784900D02*
Y835361D01*
G01X699474Y857024D02*
X682575Y840125D01*
G01X701700Y856810D02*
X684300Y839410D01*
G01X723600Y870868D02*
X692700Y839968D01*
G01X714500Y865200D02*
X688800Y839500D01*
G01X727472Y872300D02*
X695874Y840702D01*
G01X766262Y870955D02*
Y1132038D01*
G01X774488Y862729D02*
X766262Y870955D01*
G01X764537Y881500D02*
Y1130225D01*
G01X759037Y876000D02*
X764537Y881500D01*
G01X753039Y876000D02*
X759037D01*
G01X699474Y901851D02*
Y857024D01*
G01X712760Y915137D02*
X699474Y901851D01*
G01X701700Y872700D02*
Y856810D01*
G01X723600Y872400D02*
Y870868D01*
G01X714500Y870100D02*
Y865200D01*
G01X727600Y872300D02*
X727472D01*
G01X717601Y910596D02*
Y966399D01*
G01X727143Y901054D02*
X717601Y910596D01*
G01X733895Y901054D02*
X727143D01*
G01X717601Y966399D02*
X714400Y969600D01*
G01X766262Y1132038D02*
X759700Y1138600D01*
G01X764537Y1130225D02*
X759762Y1135000D01*
G01X677700Y1224500D02*
X767987Y1134213D01*
G01X755662Y1154924D02*
X774488Y1136098D01*
G01X755662Y1230905D02*
Y1154924D01*
G01X806098Y1281341D02*
X755662Y1230905D01*
G01X744541Y1415898D02*
X799725D01*
G01X737220Y1423219D02*
X744541Y1415898D01*
G01X737220Y1446220D02*
Y1423219D01*
G01X745000Y1454000D02*
X737220Y1446220D01*
G01X745000Y1463000D02*
Y1454000D01*
G01X780216Y329535D02*
Y437260D01*
G01X788801Y324645D02*
Y438395D01*
G01X778231Y329990D02*
Y437819D01*
G01X776506Y330705D02*
Y438874D01*
G01X786100Y438134D02*
Y326587D01*
G01X781941Y436521D02*
Y328820D01*
G01X797690Y454734D02*
Y516485D01*
G01X780216Y437260D02*
X797690Y454734D01*
G01X803910Y453504D02*
Y517890D01*
G01X788801Y438395D02*
X803910Y453504D01*
G01X795706Y455294D02*
Y515663D01*
G01X778231Y437819D02*
X795706Y455294D01*
G01X786609Y461921D02*
X787971D01*
G01X770798Y446110D02*
X786609Y461921D01*
G01X858740Y471627D02*
Y486430D01*
G01X863661Y466706D02*
X858740Y471627D01*
G01X769300Y435050D02*
X791971Y457721D01*
G01X789878Y464028D02*
X791971Y466121D01*
G01X785670Y464028D02*
X789878D01*
G01X769582Y447940D02*
X785670Y464028D01*
G01X861523Y472714D02*
Y487960D01*
G01X861522Y472713D02*
X861523Y472714D01*
G01X861522Y471285D02*
Y472713D01*
G01X865386Y467421D02*
X861522Y471285D01*
G01X789878Y459828D02*
X791971Y461921D01*
G01X787207Y459828D02*
X789878D01*
G01X771159Y443780D02*
X787207Y459828D01*
G01X785306Y466121D02*
X787971D01*
G01X768850Y449665D02*
X785306Y466121D01*
G01X793981Y456349D02*
Y514948D01*
G01X776506Y438874D02*
X793981Y456349D01*
G01X802185Y454219D02*
X786100Y438134D01*
G01X802185Y517175D02*
Y454219D01*
G01X770545Y440295D02*
X787971Y457721D01*
G01X800244Y454824D02*
X781941Y436521D01*
G01X800244Y516371D02*
Y454824D01*
G01X768000Y553800D02*
Y705600D01*
G01X803910Y517890D02*
X768000Y553800D01*
G01X858886Y490597D02*
Y599833D01*
G01X861523Y487960D02*
X858886Y490597D01*
G01X860611Y491312D02*
Y598101D01*
G01X863248Y488675D02*
X860611Y491312D01*
G01X798214Y640488D02*
Y668833D01*
G01X798475Y640227D02*
X798214Y640488D01*
G01X858886Y599833D02*
X863148Y604095D01*
G01X796489Y641590D02*
Y669548D01*
G01X794883Y639984D02*
X796489Y641590D01*
G01X860611Y598101D02*
X864873Y602363D01*
G01X794956Y756227D02*
Y764556D01*
G01X799913Y751270D02*
X794956Y756227D01*
G01X799913Y670532D02*
Y751270D01*
G01X798214Y668833D02*
X799913Y670532D01*
G01X793788Y684812D02*
X796200Y682400D01*
G01X793788Y752255D02*
Y684812D01*
G01X786289Y759754D02*
X793788Y752255D01*
G01X786289Y862408D02*
Y759754D01*
G01X778987Y756363D02*
Y830713D01*
G01X786487Y748863D02*
X778987Y756363D01*
G01X786487Y672837D02*
Y748863D01*
G01X791243Y668081D02*
X786487Y672837D01*
G01X784762Y748038D02*
X777300Y755500D01*
G01X784762Y669618D02*
Y748038D01*
G01X788160Y666220D02*
X784762Y669618D01*
G01X788212Y682293D02*
X789442Y681063D01*
G01X788212Y749578D02*
Y682293D01*
G01X780712Y757078D02*
X788212Y749578D01*
G01X780712Y835100D02*
Y757078D01*
G01X837709Y684499D02*
Y681095D01*
G01X838387Y685177D02*
X837709Y684499D01*
G01X838387Y689154D02*
Y685177D01*
G01X841680Y692447D02*
X838387Y689154D01*
G01X841680Y792351D02*
Y692447D01*
G01X793231Y755512D02*
Y762769D01*
G01X798188Y750555D02*
X793231Y755512D01*
G01X798188Y671247D02*
Y750555D01*
G01X796489Y669548D02*
X798188Y671247D01*
G01X794956Y764556D02*
X795300Y764900D01*
G01X774488Y838884D02*
Y862729D01*
G01X776000Y837372D02*
X774488Y838884D01*
G01X776000Y833700D02*
Y837372D01*
G01X778987Y830713D02*
X776000Y833700D01*
G01X776213Y839599D02*
X780712Y835100D01*
G01X776213Y863444D02*
Y839599D01*
G01X839321Y794710D02*
X841680Y792351D01*
G01X839321Y833219D02*
Y794710D01*
G01X838790Y833750D02*
X839321Y833219D01*
G01X838790Y851112D02*
Y833750D01*
G01X841288Y853610D02*
X838790Y851112D01*
G01X841288Y862193D02*
Y853610D01*
G01X793231Y762769D02*
X791500Y764500D01*
G01X774488Y874209D02*
X786289Y862408D01*
G01X774488Y1136098D02*
Y874209D01*
G01X848400Y907540D02*
Y974100D01*
G01X855825Y900115D02*
X848400Y907540D01*
G01X855825Y895875D02*
Y900115D01*
G01X860100Y891600D02*
X855825Y895875D01*
G01X860100Y885054D02*
Y891600D01*
G01X870200Y874954D02*
X860100Y885054D01*
G01X767987Y871670D02*
X776213Y863444D01*
G01X767987Y1134213D02*
Y871670D01*
G01X832773Y870708D02*
X841288Y862193D01*
G01X832773Y924269D02*
Y870708D01*
G01X820040Y937003D02*
X832773Y924269D01*
G01X818440Y938603D02*
X820040Y937003D01*
G01X818440Y968969D02*
Y938603D01*
G01X815216Y972193D02*
X818440Y968969D01*
G01X815216Y1152446D02*
Y972193D01*
G01X815217Y1152447D02*
X815216Y1152446D01*
G01X815217Y1157241D02*
Y1152447D01*
G01X815216Y1157242D02*
X815217Y1157241D01*
G01X815216Y1157243D02*
Y1157242D01*
G01X808311Y1164148D02*
X815216Y1157243D01*
G01X808310Y1164148D02*
X808311D01*
G01X779924Y1192534D02*
X808310Y1164148D01*
G01X779924Y1242985D02*
Y1192534D01*
G01X806098Y1409525D02*
Y1281341D01*
G01X814674Y1277735D02*
X779924Y1242985D01*
G01X814674Y1415658D02*
Y1277735D01*
G01X799725Y1415898D02*
X806098Y1409525D01*
G01X778360Y1451972D02*
X814674Y1415658D01*
G01X772361Y1451972D02*
X778360D01*
G01X902194Y268204D02*
Y344418D01*
G01X897769Y263779D02*
X902194Y268204D01*
G01X897638Y263779D02*
X897769D01*
G01X900219Y270269D02*
Y346373D01*
G01X898060Y268110D02*
X900219Y270269D01*
G01X897638Y268110D02*
X898060D01*
G01X909290Y277990D02*
Y333188D01*
G01X904725Y273425D02*
X909290Y277990D01*
G01X904725Y272835D02*
Y273425D01*
G01X894680Y261226D02*
Y289710D01*
G01X897638Y258268D02*
X894680Y261226D01*
G01X890552Y282677D02*
X882139Y291090D01*
G01X907315Y280615D02*
Y329695D01*
G01X904725Y278025D02*
X907315Y280615D01*
G01X904725Y277165D02*
Y278025D01*
G01X910330Y359080D02*
Y363490D01*
G01X904172Y352922D02*
X910330Y359080D01*
G01X904172Y346396D02*
Y352922D01*
G01X902194Y344418D02*
X904172Y346396D01*
G01X900196Y352286D02*
X908340Y360430D01*
G01X900196Y346396D02*
Y352286D01*
G01X900219Y346373D02*
X900196Y346396D01*
G01X888206Y312574D02*
Y418200D01*
G01X889757Y311023D02*
X888206Y312574D01*
G01X890552Y311023D02*
X889757D01*
G01X909290Y333188D02*
X909236Y333242D01*
G01X893115Y291275D02*
Y415731D01*
G01X894680Y289710D02*
X893115Y291275D01*
G01X882139Y330498D02*
X882823Y331182D01*
G01X882139Y291090D02*
Y330498D01*
G01X907315Y329695D02*
X906486Y330524D01*
G01X895090Y294674D02*
Y416196D01*
G01X897638Y292126D02*
X895090Y294674D01*
G01X863661Y442744D02*
Y466706D01*
G01X865680Y440725D02*
X863661Y442744D01*
G01X865681Y440725D02*
X865680D01*
G01X888206Y418200D02*
X865681Y440725D01*
G01X865386Y443459D02*
Y467421D01*
G01X866395Y442450D02*
X865386Y443459D01*
G01X866396Y442450D02*
X866395D01*
G01X893115Y415731D02*
X866396Y442450D01*
G01X863248Y471999D02*
Y488675D01*
G01X867111Y468136D02*
X863248Y471999D01*
G01X867111Y444175D02*
Y468136D01*
G01X895090Y416196D02*
X867111Y444175D01*
G01X872300Y633600D02*
X870200Y631500D01*
G01X872300Y798400D02*
Y633600D01*
G01X863148Y618308D02*
X863430Y618590D01*
G01X863148Y604095D02*
Y618308D01*
G01X868200Y632460D02*
Y666299D01*
G01X865590Y629850D02*
X868200Y632460D01*
G01X865590Y613460D02*
Y629850D01*
G01X864873Y612743D02*
X865590Y613460D01*
G01X864873Y602363D02*
Y612743D01*
G01X870308Y668407D02*
Y799219D01*
G01X868200Y666299D02*
X870308Y668407D01*
G01X870200Y852203D02*
Y874954D01*
G01X874256Y848147D02*
X870200Y852203D01*
G01X874256Y800356D02*
Y848147D01*
G01X872600Y798700D02*
X874256Y800356D01*
G01X872600Y798700D02*
X872300Y798400D01*
G01X866655Y852937D02*
Y855100D01*
G01X872531Y847061D02*
X866655Y852937D01*
G01X872531Y801442D02*
Y847061D01*
G01X870308Y799219D02*
X872531Y801442D01*
G01X1147440Y485240D02*
Y473040D01*
G01X1141432Y470222D02*
X1139590Y468380D01*
G01X1141432Y486552D02*
Y470222D01*
G01X1130800Y487400D02*
Y472900D01*
G01X1136762Y447611D02*
X1136000Y446849D01*
G01X1163021Y447611D02*
X1136762D01*
G01X1145452Y470252D02*
X1143720Y468520D01*
G01X1145452Y485692D02*
Y470252D01*
G01X1136100Y460288D02*
X1158052D01*
G01X1135310Y488210D02*
Y472820D01*
G01X1092487Y452987D02*
X1088000Y448500D01*
G01X1101030Y452987D02*
X1092487D01*
G01X1101231Y452786D02*
X1101030Y452987D01*
G01X1160876Y452786D02*
X1101231D01*
G01X1143420Y486100D02*
Y472900D01*
G01X1139330Y486890D02*
Y472820D01*
G01X1134336Y449336D02*
X1162306D01*
G01X1131800Y446800D02*
X1134336Y449336D01*
G01X1094862Y451262D02*
X1092000Y448400D01*
G01X1100314Y451262D02*
X1094862D01*
G01X1100515Y451061D02*
X1100314Y451262D01*
G01X1161591Y451061D02*
X1100515D01*
G01X1096188Y454712D02*
X1095100Y455800D01*
G01X1101745Y454712D02*
X1096188D01*
G01X1101946Y454511D02*
X1101745Y454712D01*
G01X1160161Y454511D02*
X1101946D01*
G01X1137342Y470312D02*
X1135410Y468380D01*
G01X1137342Y487342D02*
Y470312D01*
G01X1155086Y492886D02*
X1147440Y485240D01*
G01X1148722Y493842D02*
X1141432Y486552D01*
G01X1148722Y494302D02*
Y493842D01*
G01X1149236Y494816D02*
X1148722Y494302D01*
G01X1142316Y498916D02*
X1130800Y487400D01*
G01X1142316Y532024D02*
Y498916D01*
G01X1142413Y532121D02*
X1142316Y532024D01*
G01X1142413Y572855D02*
Y532121D01*
G01X1153361Y493601D02*
X1145452Y485692D01*
G01X1144061Y496961D02*
X1135310Y488210D01*
G01X1144061Y531329D02*
Y496961D01*
G01X1144138Y531406D02*
X1144061Y531329D01*
G01X1144138Y573570D02*
Y531406D01*
G01X1150942Y493622D02*
X1143420Y486100D01*
G01X1146997Y494557D02*
X1139330Y486890D01*
G01X1146997Y495017D02*
Y494557D01*
G01X1147511Y495531D02*
X1146997Y495017D01*
G01X1147511Y529899D02*
Y495531D01*
G01X1147588Y529976D02*
X1147511Y529899D01*
G01X1147588Y575000D02*
Y529976D01*
G01X1145272Y495272D02*
X1137342Y487342D01*
G01X1145272Y495732D02*
Y495272D01*
G01X1145786Y496246D02*
X1145272Y495732D01*
G01X1145786Y530614D02*
Y496246D01*
G01X1145863Y530691D02*
X1145786Y530614D01*
G01X1145863Y574285D02*
Y530691D01*
G01X1125025Y622039D02*
Y621993D01*
G01X1135331Y632345D02*
X1125025Y622039D01*
G01X1135331Y688318D02*
Y632345D01*
G01X1142291Y572977D02*
X1142413Y572855D01*
G01X1142291Y666664D02*
Y572977D01*
G01X1144016Y573692D02*
X1144138Y573570D01*
G01X1144016Y695922D02*
Y573692D01*
G01X1147466Y575122D02*
X1147588Y575000D01*
G01X1147466Y698694D02*
Y575122D01*
G01X1145741Y574407D02*
X1145863Y574285D01*
G01X1145741Y697470D02*
Y574407D01*
G01X1136361Y722564D02*
X1154366Y704559D01*
G01X1117612Y722564D02*
X1136361D01*
G01X1115105Y720057D02*
X1117612Y722564D01*
G01X1134760Y688889D02*
X1135331Y688318D01*
G01X1117927Y688889D02*
X1134760D01*
G01X1115105Y691711D02*
X1117927Y688889D01*
G01X1138186Y710414D02*
X1149191Y699409D01*
G01X1118362Y710414D02*
X1138186D01*
G01X1115806Y712970D02*
X1118362Y710414D01*
G01X1113530Y712970D02*
X1115806D01*
G01X1137355Y671600D02*
X1142291Y666664D01*
G01X1137355Y693265D02*
Y671600D01*
G01X1134720Y695900D02*
X1137355Y693265D01*
G01X1116427Y695900D02*
X1134720D01*
G01X1113530Y698797D02*
X1116427Y695900D01*
G01X1137283Y737000D02*
X1161266Y713017D01*
G01X1117875Y737000D02*
X1137283D01*
G01X1115105Y734230D02*
X1117875Y737000D01*
G01X1138813Y729600D02*
X1157816Y710597D01*
G01X1121498Y729600D02*
X1138813D01*
G01X1119042Y727144D02*
X1121498Y729600D01*
G01X1139254Y731600D02*
X1159541Y711313D01*
G01X1112223Y731600D02*
X1139254D01*
G01X1109593Y734230D02*
X1112223Y731600D01*
G01X1138986Y717499D02*
X1152641Y703844D01*
G01X1112151Y717499D02*
X1138986D01*
G01X1109593Y720057D02*
X1112151Y717499D01*
G01X1138599Y701339D02*
X1144016Y695922D01*
G01X1121584Y701339D02*
X1138599D01*
G01X1119042Y698797D02*
X1121584Y701339D01*
G01X1136706Y724659D02*
X1153048Y708317D01*
G01X1116341Y724659D02*
X1136706D01*
G01X1113856Y727144D02*
X1116341Y724659D01*
G01X1113530Y727144D02*
X1113856D01*
G01X1138481Y715524D02*
X1150916Y703089D01*
G01X1121596Y715524D02*
X1138481D01*
G01X1119042Y712970D02*
X1121596Y715524D01*
G01X1137746Y708414D02*
X1147466Y698694D01*
G01X1117635Y708414D02*
X1137746D01*
G01X1115105Y705884D02*
X1117635Y708414D01*
G01X1139842Y703369D02*
X1145741Y697470D01*
G01X1114384Y703369D02*
X1139842D01*
G01X1111869Y705884D02*
X1114384Y703369D01*
G01X1109593Y705884D02*
X1111869D01*
G01X1141606Y873197D02*
X1150355Y864448D01*
G01X1117870Y873197D02*
X1141606D01*
G01X1115105Y875962D02*
X1117870Y873197D01*
G01X1116372Y936900D02*
X1113530Y939742D01*
G01X1132661Y936900D02*
X1116372D01*
G01X1158599Y910962D02*
X1132661Y936900D01*
G01X1139388Y945688D02*
X1164175Y920901D01*
G01X1138386Y945688D02*
X1139388D01*
G01X1130374Y953700D02*
X1138386Y945688D01*
G01X1101600Y953700D02*
X1130374D01*
G01X1156110Y475710D02*
Y473330D01*
G01X1195581Y480171D02*
X1163021Y447611D01*
G01X1154122Y469992D02*
X1152600Y468470D01*
G01X1154122Y477922D02*
Y469992D01*
G01X1197599Y446665D02*
Y725907D01*
G01X1242982Y401282D02*
X1197599Y446665D01*
G01X1243934Y401282D02*
X1242982D01*
G01X1262945Y382271D02*
X1243934Y401282D01*
G01X1158052Y460288D02*
X1183105Y485341D01*
G01X1190406Y482316D02*
X1160876Y452786D01*
G01X1162306Y449336D02*
X1193856Y480886D01*
G01X1192131Y481601D02*
X1161591Y451061D01*
G01X1188681Y483031D02*
X1160161Y454511D01*
G01X1155086Y577262D02*
Y492886D01*
G01X1226463Y519194D02*
Y702630D01*
G01X1282482Y463175D02*
X1226463Y519194D01*
G01X1149236Y529184D02*
Y494816D01*
G01X1149313Y529261D02*
X1149236Y529184D01*
G01X1149313Y575715D02*
Y529261D01*
G01X1161986Y481586D02*
X1156110Y475710D01*
G01X1161986Y580122D02*
Y481586D01*
G01X1223013Y517764D02*
X1281052Y459725D01*
G01X1223013Y698406D02*
Y517764D01*
G01X1195581Y728089D02*
Y480171D01*
G01X1150234Y481623D02*
X1149964D01*
G01X1158536Y489925D02*
X1150234Y481623D01*
G01X1158536Y578692D02*
Y489925D01*
G01X1160261Y484061D02*
X1154122Y477922D01*
G01X1160261Y579407D02*
Y484061D01*
G01X1201428Y520995D02*
Y699275D01*
G01X1284802Y437621D02*
X1201428Y520995D01*
G01X1243202Y485464D02*
X1289216Y439450D01*
G01X1206638Y522027D02*
X1243202Y485464D01*
G01X1206638Y697132D02*
Y522027D01*
G01X1208363Y522937D02*
X1291078Y440222D01*
G01X1208363Y693645D02*
Y522937D01*
G01X1221288Y517049D02*
X1280337Y458000D01*
G01X1221288Y696294D02*
Y517049D01*
G01X1153361Y576547D02*
Y493601D01*
G01X1183105Y485341D02*
Y735240D01*
G01X1190406Y730235D02*
Y482316D01*
G01X1150900Y485200D02*
Y485100D01*
G01X1156811Y491111D02*
X1150900Y485200D01*
G01X1156811Y577977D02*
Y491111D01*
G01X1150942Y494082D02*
Y493622D01*
G01X1150961Y494101D02*
X1150942Y494082D01*
G01X1150961Y528469D02*
Y494101D01*
G01X1151038Y528546D02*
X1150961Y528469D01*
G01X1151038Y576430D02*
Y528546D01*
G01X1228188Y519909D02*
X1283197Y464900D01*
G01X1228188Y704294D02*
Y519909D01*
G01X1204114Y521552D02*
Y697805D01*
G01X1287095Y438571D02*
X1204114Y521552D01*
G01X1193856Y480886D02*
Y728804D01*
G01X1192131Y729519D02*
Y481601D01*
G01X1224738Y518479D02*
X1281767Y461450D01*
G01X1224738Y700967D02*
Y518479D01*
G01X1188681Y730950D02*
Y483031D01*
G01X1154366Y577982D02*
X1155086Y577262D01*
G01X1154366Y704559D02*
Y577982D01*
G01X1149191Y575837D02*
X1149313Y575715D01*
G01X1149191Y699409D02*
Y575837D01*
G01X1161266Y580842D02*
X1161986Y580122D01*
G01X1161266Y713017D02*
Y580842D01*
G01X1177336Y597778D02*
X1177350Y597792D01*
G01X1177336Y606300D02*
Y597778D01*
G01X1174141Y609495D02*
X1177336Y606300D01*
G01X1174141Y728575D02*
Y609495D01*
G01X1241124Y663456D02*
X1238302Y666278D01*
G01X1241124Y643436D02*
Y663456D01*
G01X1265560Y619000D02*
X1241124Y643436D01*
G01X1157816Y579412D02*
X1158536Y578692D01*
G01X1157816Y710597D02*
Y579412D01*
G01X1159541Y580127D02*
X1160261Y579407D01*
G01X1159541Y711313D02*
Y580127D01*
G01X1152641Y577267D02*
X1153361Y576547D01*
G01X1152641Y703844D02*
Y577267D01*
G01X1236690Y642370D02*
Y664290D01*
G01X1266973Y612087D02*
X1236690Y642370D01*
G01X1232490Y637870D02*
X1323430Y546930D01*
G01X1232490Y664290D02*
Y637870D01*
G01X1156091Y578697D02*
X1156811Y577977D01*
G01X1156091Y705277D02*
Y578697D01*
G01X1150916Y576552D02*
X1151038Y576430D01*
G01X1150916Y703089D02*
Y576552D01*
G01X1244181Y644879D02*
X1265560Y623500D01*
G01X1244181Y663540D02*
Y644879D01*
G01X1239231Y668490D02*
X1244181Y663540D01*
G01X1232490Y753784D02*
X1217124Y769150D01*
G01X1232490Y685290D02*
Y753784D01*
G01X1210410Y721918D02*
X1212587Y724095D01*
G01X1210410Y718683D02*
Y721918D01*
G01X1226463Y702630D02*
X1210410Y718683D01*
G01X1206254Y715165D02*
X1223013Y698406D01*
G01X1206254Y726162D02*
Y715165D01*
G01X1212587Y732495D02*
X1206254Y726162D01*
G01X1150355Y752361D02*
X1174141Y728575D01*
G01X1150355Y864448D02*
Y752361D01*
G01X1234702Y666278D02*
X1232490Y668490D01*
G01X1238302Y666278D02*
X1234702D01*
G01X1230502Y683078D02*
X1232490Y681090D01*
G01X1230502Y751437D02*
Y683078D01*
G01X1215318Y766621D02*
X1230502Y751437D01*
G01X1212587Y745095D02*
X1195581Y728089D01*
G01X1234478Y670702D02*
X1232490Y672690D01*
G01X1240691Y670702D02*
X1234478D01*
G01X1247717Y663676D02*
X1240691Y670702D01*
G01X1201428Y699275D02*
X1206414Y704261D01*
G01X1207468Y697962D02*
X1206638Y697132D01*
G01X1210283Y695565D02*
X1208363Y693645D01*
G01X1204079Y713503D02*
X1221288Y696294D01*
G01X1204079Y728187D02*
Y713503D01*
G01X1212587Y736695D02*
X1204079Y728187D01*
G01X1197599Y725907D02*
X1212587Y740895D01*
G01X1241264Y672690D02*
X1251015Y662939D01*
G01X1236690Y672690D02*
X1241264D01*
G01X1158599Y759746D02*
Y910962D01*
G01X1183105Y735240D02*
X1158599Y759746D01*
G01X1190528Y730357D02*
X1190406Y730235D01*
G01X1190528Y738144D02*
Y730357D01*
G01X1190406Y738266D02*
X1190528Y738144D01*
G01X1190406Y738267D02*
Y738266D01*
G01X1187764Y740909D02*
X1190406Y738267D01*
G01X1187763Y740909D02*
X1187764D01*
G01X1186130Y742542D02*
X1187763Y740909D01*
G01X1186129Y742542D02*
X1186130D01*
G01X1166826Y761845D02*
X1186129Y742542D01*
G01X1154241Y707127D02*
X1156091Y705277D01*
G01X1154240Y707127D02*
X1154241D01*
G01X1154059Y707308D02*
X1154240Y707127D01*
G01X1154058Y707308D02*
X1154059D01*
G01X1153049Y708317D02*
X1154058Y707308D01*
G01X1153048Y708317D02*
X1153049D01*
G01X1212587Y719895D02*
X1228188Y704294D01*
G01X1207917Y701608D02*
X1209931D01*
G01X1204114Y697805D02*
X1207917Y701608D01*
G01X1236690Y668490D02*
X1239231D01*
G01X1194149Y730857D02*
X1212587Y749295D01*
G01X1194149Y729097D02*
Y730857D01*
G01X1193856Y728804D02*
X1194149Y729097D01*
G01X1192253Y729641D02*
X1192131Y729519D01*
G01X1192253Y738859D02*
Y729641D01*
G01X1192131Y738981D02*
X1192253Y738859D01*
G01X1192131Y738983D02*
Y738981D01*
G01X1191122Y739992D02*
X1192131Y738983D01*
G01X1191121Y739992D02*
X1191122D01*
G01X1188479Y742634D02*
X1191121Y739992D01*
G01X1188478Y742634D02*
X1188479D01*
G01X1186845Y744267D02*
X1188478Y742634D01*
G01X1186844Y744267D02*
X1186845D01*
G01X1168552Y762559D02*
X1186844Y744267D01*
G01X1208620Y717085D02*
X1224738Y700967D01*
G01X1208620Y724328D02*
Y717085D01*
G01X1212587Y728295D02*
X1208620Y724328D01*
G01X1188803Y731072D02*
X1188681Y730950D01*
G01X1188803Y737428D02*
Y731072D01*
G01X1188681Y737550D02*
X1188803Y737428D01*
G01X1188681Y737552D02*
Y737550D01*
G01X1187049Y739184D02*
X1188681Y737552D01*
G01X1187048Y739184D02*
X1187049D01*
G01X1185416Y740816D02*
X1187048Y739184D01*
G01X1185415Y740816D02*
X1185416D01*
G01X1164387Y761844D02*
X1185415Y740816D01*
G01X1172002Y788887D02*
Y876452D01*
G01X1191739Y769150D02*
X1172002Y788887D01*
G01X1217124Y769150D02*
X1191739D01*
G01X1332660Y798020D02*
X1179690D01*
G01X1191828Y766621D02*
X1215318D01*
G01X1170277Y788172D02*
X1191828Y766621D01*
G01X1170277Y881827D02*
Y788172D01*
G01X1197770Y783170D02*
X1356170D01*
G01X1190995Y776395D02*
X1197770Y783170D01*
G01X1173990Y820290D02*
Y797760D01*
G01X1178700Y825000D02*
X1173990Y820290D01*
G01X1217111Y825000D02*
X1178700D01*
G01X1180420Y790880D02*
X1180520D01*
G01X1176900Y794400D02*
X1180420Y790880D01*
G01X1176900Y798041D02*
Y794400D01*
G01X1178867Y800008D02*
X1176900Y798041D01*
G01X1178908Y800008D02*
X1178867D01*
G01X1179900Y801000D02*
X1178908Y800008D01*
G01X1333200Y801000D02*
X1179900D01*
G01X1166826Y763273D02*
Y761845D01*
G01X1166827Y763274D02*
X1166826Y763273D01*
G01X1166827Y891377D02*
Y763274D01*
G01X1186690Y791440D02*
X1339240D01*
G01X1168552Y886502D02*
Y762559D01*
G01X1164387Y919687D02*
Y761844D01*
G01X1321284Y804960D02*
X1177300D01*
G01X1172002Y876452D02*
X1184750Y889200D01*
G01Y896300D02*
X1170277Y881827D01*
G01X1181550Y906100D02*
X1166827Y891377D01*
G01X1177143Y895093D02*
X1168552Y886502D01*
G01X1178659Y895093D02*
X1177143D01*
G01X1180090Y896524D02*
X1178659Y895093D01*
G01X1164175Y919899D02*
X1164387Y919687D01*
G01X1164175Y920901D02*
Y919899D01*
G01X1256800Y211832D02*
Y132400D01*
G01X1270877Y225909D02*
X1256800Y211832D01*
G01X1270877Y340310D02*
Y225909D01*
G01X1329832Y337374D02*
X1384500Y282706D01*
G01X1276253Y337374D02*
X1329832D01*
G01X1271111Y342516D02*
X1276253Y337374D01*
G01X1271111Y364867D02*
Y342516D01*
G01X1271112Y364868D02*
X1271111Y364867D01*
G01X1271112Y370114D02*
Y364868D01*
G01X1274694Y373696D02*
X1271112Y370114D01*
G01X1274694Y392512D02*
Y373696D01*
G01X1284802Y353771D02*
Y437621D01*
G01X1292313Y346260D02*
X1284802Y353771D01*
G01X1357568Y346260D02*
X1292313D01*
G01X1294142Y350674D02*
X1359397D01*
G01X1289216Y355600D02*
X1294142Y350674D01*
G01X1289216Y439450D02*
Y355600D01*
G01X1294914Y352536D02*
X1360169D01*
G01X1291078Y356372D02*
X1294914Y352536D01*
G01X1291078Y440222D02*
Y356372D01*
G01X1327612Y385956D02*
X1341324Y372244D01*
G01X1278144Y372266D02*
Y400270D01*
G01X1274562Y368684D02*
X1278144Y372266D01*
G01X1274562Y343945D02*
Y368684D01*
G01X1277683Y340824D02*
X1274562Y343945D01*
G01X1331262Y340824D02*
X1277683D01*
G01X1335070Y337016D02*
X1331262Y340824D01*
G01X1341398Y337016D02*
X1335070D01*
G01X1276419Y372981D02*
Y399555D01*
G01X1272837Y369399D02*
X1276419Y372981D01*
G01X1272837Y364153D02*
Y369399D01*
G01X1272836Y364152D02*
X1272837Y364153D01*
G01X1272836Y362724D02*
Y364152D01*
G01X1272837Y362723D02*
X1272836Y362724D01*
G01X1272837Y343230D02*
Y362723D01*
G01X1276968Y339099D02*
X1272837Y343230D01*
G01X1330547Y339099D02*
X1276968D01*
G01X1338150Y331496D02*
X1330547Y339099D01*
G01X1344478Y331496D02*
X1338150D01*
G01X1262945Y377600D02*
Y382271D01*
G01X1269386Y341801D02*
X1270877Y340310D01*
G01X1269386Y364152D02*
Y341801D01*
G01X1269385Y364153D02*
X1269386Y364152D01*
G01X1269385Y365581D02*
Y364153D01*
G01X1269387Y365583D02*
X1269385Y365581D01*
G01X1269387Y370829D02*
Y365583D01*
G01X1270877Y372319D02*
X1269387Y370829D01*
G01X1270877Y388223D02*
Y372319D01*
G01X1287095Y354721D02*
Y438571D01*
G01X1293263Y348553D02*
X1287095Y354721D01*
G01X1358518Y348553D02*
X1293263D01*
G01X1279869Y371551D02*
Y406649D01*
G01X1276287Y367969D02*
X1279869Y371551D01*
G01X1276287Y344661D02*
Y367969D01*
G01X1278399Y342549D02*
X1276287Y344661D01*
G01X1331977Y342549D02*
X1278399D01*
G01X1335785Y338741D02*
X1331977Y342549D01*
G01X1347777Y338741D02*
X1335785D01*
G01X1336500Y340466D02*
X1351144D01*
G01X1332692Y344274D02*
X1336500Y340466D01*
G01X1279114Y344274D02*
X1332692D01*
G01X1278012Y345376D02*
X1279114Y344274D01*
G01X1278012Y367254D02*
Y345376D01*
G01X1281594Y370836D02*
X1278012Y367254D01*
G01X1281594Y410016D02*
Y370836D01*
G01X1263603Y403603D02*
X1274694Y392512D01*
G01X1263603Y407648D02*
Y403603D01*
G01X1247949Y423302D02*
X1263603Y407648D01*
G01X1488715Y463175D02*
X1282482D01*
G01X1335412Y459725D02*
X1413791Y381346D01*
G01X1281052Y459725D02*
X1335412D01*
G01X1327612Y444023D02*
Y385956D01*
G01X1313635Y458000D02*
X1327612Y444023D01*
G01X1280337Y458000D02*
X1313635D01*
G01X1253400Y428086D02*
X1245959Y435527D01*
G01X1253400Y425014D02*
Y428086D01*
G01X1278144Y400270D02*
X1253400Y425014D01*
G01X1250911Y425423D02*
X1250648Y425686D01*
G01X1250911Y425063D02*
Y425423D01*
G01X1276419Y399555D02*
X1250911Y425063D01*
G01X1258887Y400213D02*
X1270877Y388223D01*
G01X1258887Y407282D02*
Y400213D01*
G01X1245567Y420602D02*
X1258887Y407282D01*
G01X1283197Y464900D02*
X1492501D01*
G01X1281767Y461450D02*
X1484750D01*
G01X1279869Y406649D02*
X1265295Y421223D01*
G01X1257000Y434610D02*
X1281594Y410016D01*
G01X1257000Y434600D02*
Y434610D01*
G01X1323430Y506820D02*
X1325500Y504750D01*
G01X1323430Y546930D02*
Y506820D01*
G01X1488417Y619000D02*
X1265560D01*
G01X1247717Y646648D02*
Y663676D01*
G01X1267365Y627000D02*
X1247717Y646648D01*
G01X1728842Y627000D02*
X1267365D01*
G01X1371118Y612087D02*
X1266973D01*
G01X1266305Y630500D02*
X1745500D01*
G01X1251015Y645790D02*
X1266305Y630500D01*
G01X1251015Y662939D02*
Y645790D01*
G01X1265560Y623500D02*
X1608130D01*
G01X1356608Y821968D02*
X1332660Y798020D01*
G01X1357200Y825000D02*
X1333200Y801000D01*
G01X1339240Y791440D02*
X1356000Y808200D01*
G01X1341324Y825000D02*
X1321284Y804960D01*
G01X1325500Y957250D02*
Y907000D01*
G01X1384500Y143800D02*
X1376700Y136000D01*
G01X1384500Y282706D02*
Y143800D01*
G01X1490030Y213798D02*
X1357568Y346260D01*
G01X1359397Y350674D02*
X1491859Y218212D01*
G01X1360169Y352536D02*
X1492631Y220074D01*
G01X1470201Y208213D02*
X1341398Y337016D01*
G01X1501300Y174674D02*
X1344478Y331496D01*
G01X1490980Y216091D02*
X1358518Y348553D01*
G01X1476580Y209938D02*
X1347777Y338741D01*
G01X1351144Y340466D02*
X1479624Y211986D01*
G01X1413791Y381346D02*
X1456434D01*
G01X1448512Y534693D02*
X1371118Y612087D01*
G01X1465806Y821968D02*
X1356608D01*
G01X1371300Y798300D02*
X1687261D01*
G01X1356170Y783170D02*
X1371300Y798300D01*
G01X1465536Y825000D02*
X1357200D01*
G01X1356000Y808200D02*
X1683812D01*
G01X1501300Y136100D02*
Y174674D01*
G01X1606088Y213798D02*
X1490030D01*
G01X1491859Y218212D02*
X1611091D01*
G01X1492631Y220074D02*
X1611669D01*
G01X1570787Y208213D02*
X1470201D01*
G01X1609882Y216091D02*
X1490980D01*
G01X1576236Y209938D02*
X1476580D01*
G01X1479624Y211986D02*
X1578476D01*
G01X1456434Y381346D02*
X1465536Y372244D01*
G01X1537395Y414495D02*
X1488715Y463175D01*
G01X1492501Y464900D02*
X1539277Y418124D01*
G01X1484750Y461450D02*
X1573956Y372244D01*
G01X1448512Y505738D02*
Y534693D01*
G01X1449500Y504750D02*
X1448512Y505738D01*
G01X1573012Y534405D02*
X1488417Y619000D01*
G01X1468838Y825000D02*
X1465806Y821968D01*
G01X1591400Y825000D02*
X1468838D01*
G01X1443992Y951742D02*
Y904962D01*
G01X1450100Y957850D02*
X1443992Y951742D01*
G01X1450100Y959500D02*
Y957850D01*
G01X1625300Y153700D02*
X1570787Y208213D01*
G01X1625300Y136000D02*
Y153700D01*
G01X1621379Y164795D02*
X1576236Y209938D01*
G01X1723205Y164795D02*
X1621379D01*
G01X1621799Y168663D02*
X1808828D01*
G01X1578476Y211986D02*
X1621799Y168663D01*
G01X1616100Y203786D02*
X1606088Y213798D01*
G01X1611091Y218212D02*
X1634216Y195087D01*
G01X1611669Y220074D02*
X1634931Y196812D01*
G01X1647033Y178940D02*
X1609882Y216091D01*
G01X1573956Y372244D02*
X1589749D01*
G01X1697416Y414495D02*
X1537395D01*
G01X1539277Y418124D02*
X1696227D01*
G01X1573012Y513177D02*
Y534405D01*
G01X1574000Y512189D02*
X1573012Y513177D01*
G01X1574000Y504750D02*
Y512189D01*
G01X1608130Y623500D02*
X1697012Y534618D01*
G01X1572900Y902900D02*
Y956150D01*
G01D02*
X1574000Y957250D01*
G01X1700197Y178940D02*
X1647033D01*
G01X1712525Y191268D02*
X1700197Y178940D01*
G01X1634216Y195087D02*
X1742891D01*
G01X1634931Y196812D02*
X1743800D01*
G01X1703008Y408903D02*
X1697416Y414495D01*
G01X1750558Y408903D02*
X1703008D01*
G01X1703723Y410628D02*
X1767114D01*
G01X1696227Y418124D02*
X1703723Y410628D01*
G01X1698000Y512189D02*
Y504750D01*
G01X1697012Y513177D02*
X1698000Y512189D01*
G01X1697012Y534618D02*
Y513177D01*
G01X1687261Y798300D02*
X1713961Y825000D01*
G01X1712261Y836649D02*
X1826525D01*
G01X1683812Y808200D02*
X1712261Y836649D01*
G01X1699520Y910680D02*
X1709500Y900700D01*
G01X1699520Y955730D02*
Y910680D01*
G01X1698000Y957250D02*
X1699520Y955730D01*
G01X1690500Y1306484D02*
X1676511Y1292495D01*
G01X1690500Y1411758D02*
Y1306484D01*
G01X1656250Y1446008D02*
X1690500Y1411758D01*
G01X1656250Y1461250D02*
Y1446008D01*
G01X1765126Y172852D02*
X1830949D01*
G01X1742891Y195087D02*
X1765126Y172852D01*
G01X1765898Y174714D02*
X1837379D01*
G01X1743800Y196812D02*
X1765898Y174714D01*
G01X1749700Y138300D02*
X1723205Y164795D01*
G01X1749700Y135600D02*
Y138300D01*
G01X1808828Y168663D02*
X1819991Y157500D01*
G01X1767114Y410628D02*
X1805142Y372600D01*
G01X1753631Y405830D02*
X1750558Y408903D01*
G01X1818000Y537842D02*
X1728842Y627000D01*
G01X1745500Y630500D02*
X1823500Y552500D01*
G01X1871405Y50495D02*
X1872900Y49000D01*
G01X1871405Y58968D02*
Y50495D01*
G01X1877767Y65330D02*
X1871405Y58968D01*
G01X1877767Y109003D02*
Y65330D01*
G01X1874500Y74822D02*
X1868600Y68922D01*
G01X1874500Y84049D02*
Y74822D01*
G01X1872525Y86024D02*
X1874500Y84049D01*
G01X1872525Y105075D02*
Y86024D01*
G01X1830949Y172852D02*
X1834018Y169783D01*
G01X1862514Y124256D02*
X1877767Y109003D01*
G01X1862514Y149579D02*
Y124256D01*
G01X1837379Y174714D02*
X1862514Y149579D01*
G01X1858800Y118800D02*
X1872525Y105075D01*
G01X1858800Y147300D02*
Y118800D01*
G01X1848600Y157500D02*
X1858800Y147300D01*
G01X1819991Y157500D02*
X1848600D01*
G01X1818000Y508750D02*
Y537842D01*
G01X1822000Y504750D02*
X1818000Y508750D01*
G01X1823500Y529000D02*
X1848500Y504000D01*
G01X1823500Y552500D02*
Y529000D01*
G01X1826525Y836649D02*
X1838174Y825000D01*
G01X1820700Y955950D02*
Y940600D01*
G01X1848500Y957000D02*
Y940200D01*
G01X1822000Y957250D02*
X1820700Y955950D01*
M02*
